FILE_TYPE = MACRO_DRAWING;
SET COLOR_WIRE YELLOW;
SET COLOR_PROP ORANGE;
SET COLOR_DOT WHITE;
SET COLOR_ARC YELLOW;
SET COLOR_BODY GREEN;
SET COLOR_NOTE PURPLE;
SET PROP_DISPLAY VALUE;
SET PAGE_NUMBER P146;
FORCEADD OFFPAGE..5
(2525 4825);
FORCEPROP 2 LAST $XR0 160 
J 0
(2270 4825);
DISPLAY 0.638298 (2270 4825);
PAINT MONO (2270 4825);
FORCEPROP 2 LAST CDS_LIB standard
J 0
(2525 4825);
PAINT MONO (2525 4825);
DISPLAY INVISIBLE (2525 4825);
FORCEPROP 1 LAST OFFPAGE TRUE
J 0
(2850 4700);
DISPLAY 0.872340 (2850 4700);
PAINT GREEN (2850 4700);
DISPLAY INVISIBLE (2850 4700);
FORCEPROP 1 LAST COMMENT_BODY TRUE
J 0
(2625 4750);
DISPLAY 0.872340 (2625 4750);
PAINT GREEN (2625 4750);
DISPLAY INVISIBLE (2625 4750);
FORCEPROP 2 LAST PATH I10
J 0
(2250 4875);
DISPLAY 1.021277 (2250 4875);
DISPLAY INVISIBLE (2250 4875);
FORCEADD OFFPAGE..1
(2525 4875);
FORCEPROP 2 LAST $XR0 159 
J 0
(2273 4875);
DISPLAY 0.638298 (2273 4875);
PAINT MONO (2273 4875);
FORCEPROP 2 LAST CDS_LIB standard
J 0
(2525 4875);
PAINT MONO (2525 4875);
DISPLAY INVISIBLE (2525 4875);
FORCEPROP 1 LAST OFFPAGE TRUE
J 0
(2850 4750);
DISPLAY 0.872340 (2850 4750);
PAINT GREEN (2850 4750);
DISPLAY INVISIBLE (2850 4750);
FORCEPROP 1 LAST COMMENT_BODY TRUE
J 0
(2650 4775);
DISPLAY 0.872340 (2650 4775);
PAINT GREEN (2650 4775);
DISPLAY INVISIBLE (2650 4775);
FORCEPROP 2 LAST PATH I11
J 0
(2250 4925);
DISPLAY 1.021277 (2250 4925);
DISPLAY INVISIBLE (2250 4925);
FORCEADD OFFPAGE..5
(2525 4925);
FORCEPROP 2 LAST $XR1 213 
J 0
(2150 4925);
DISPLAY 0.638298 (2150 4925);
PAINT MONO (2150 4925);
FORCEPROP 2 LAST $XR0 159 
J 0
(2270 4925);
DISPLAY 0.638298 (2270 4925);
PAINT MONO (2270 4925);
FORCEPROP 2 LAST CDS_LIB standard
J 0
(2525 4925);
PAINT MONO (2525 4925);
DISPLAY INVISIBLE (2525 4925);
FORCEPROP 1 LAST OFFPAGE TRUE
J 0
(2850 4800);
DISPLAY 0.872340 (2850 4800);
PAINT GREEN (2850 4800);
DISPLAY INVISIBLE (2850 4800);
FORCEPROP 1 LAST COMMENT_BODY TRUE
J 0
(2625 4850);
DISPLAY 0.872340 (2625 4850);
PAINT GREEN (2625 4850);
DISPLAY INVISIBLE (2625 4850);
FORCEPROP 2 LAST PATH I12
J 0
(2250 4975);
DISPLAY 1.021277 (2250 4975);
DISPLAY INVISIBLE (2250 4975);
FORCEADD UNIVERSAL_GND..1
(5325 225);
FORCEPROP 3 LASTPIN (5325 275) SIG_NAME GND\g
J 0
(5335 285);
DISPLAY 0.659574 (5335 285);
PAINT MONO (5335 285);
DISPLAY INVISIBLE (5335 285);
FORCEPROP 2 LAST CDS_LIB logical_power
J 0
(5325 225);
DISPLAY INVISIBLE (5325 225);
FORCEPROP 1 LAST HDL_POWER GND
J 1
(5350 150);
DISPLAY 0.872340 (5350 150);
PAINT GREEN (5350 150);
DISPLAY INVISIBLE (5350 150);
FORCEPROP 1 LAST PATH I124
J 0
(5400 225);
DISPLAY 0.872340 (5400 225);
PAINT AQUA (5400 225);
DISPLAY INVISIBLE (5400 225);
FORCEADD OFFPAGE..5
(2400 2225);
FORCEPROP 2 LAST $XR1 165 
J 0
(2025 2225);
DISPLAY 0.638298 (2025 2225);
PAINT MONO (2025 2225);
FORCEPROP 2 LAST $XR0 162 
J 0
(2145 2225);
DISPLAY 0.638298 (2145 2225);
PAINT MONO (2145 2225);
FORCEPROP 2 LAST CDS_LIB standard
J 0
(2400 2225);
PAINT MONO (2400 2225);
DISPLAY INVISIBLE (2400 2225);
FORCEPROP 1 LAST OFFPAGE TRUE
J 0
(2725 2100);
DISPLAY 0.872340 (2725 2100);
PAINT GREEN (2725 2100);
DISPLAY INVISIBLE (2725 2100);
FORCEPROP 1 LAST COMMENT_BODY TRUE
J 0
(2500 2150);
DISPLAY 0.872340 (2500 2150);
PAINT GREEN (2500 2150);
DISPLAY INVISIBLE (2500 2150);
FORCEPROP 2 LAST PATH I125
J 0
(2125 2275);
DISPLAY 1.021277 (2125 2275);
DISPLAY INVISIBLE (2125 2275);
FORCEADD OFFPAGE..5
(2225 725);
FORCEPROP 2 LAST $XR1 165 
J 0
(1820 725);
DISPLAY 0.638298 (1820 725);
PAINT MONO (1820 725);
FORCEPROP 2 LAST $XR0 162 
J 0
(1940 725);
DISPLAY 0.638298 (1940 725);
PAINT MONO (1940 725);
FORCEPROP 2 LAST CDS_LIB standard
J 0
(2225 725);
PAINT MONO (2225 725);
DISPLAY INVISIBLE (2225 725);
FORCEPROP 1 LAST OFFPAGE TRUE
J 0
(2550 600);
DISPLAY 0.872340 (2550 600);
PAINT GREEN (2550 600);
DISPLAY INVISIBLE (2550 600);
FORCEPROP 1 LAST COMMENT_BODY TRUE
J 0
(2325 650);
DISPLAY 0.872340 (2325 650);
PAINT GREEN (2325 650);
DISPLAY INVISIBLE (2325 650);
FORCEPROP 2 LAST PATH I126
J 0
(1950 775);
DISPLAY 1.021277 (1950 775);
DISPLAY INVISIBLE (1950 775);
FORCEADD OFFPAGE..2
(6775 2225);
FORCEPROP 2 LAST $XR1 165 
J 0
(7084 2225);
DISPLAY 0.638298 (7084 2225);
PAINT MONO (7084 2225);
FORCEPROP 2 LAST $XR0 162 
J 0
(6964 2225);
DISPLAY 0.638298 (6964 2225);
PAINT MONO (6964 2225);
FORCEPROP 2 LAST CDS_LIB standard
J 0
(6775 2225);
DISPLAY INVISIBLE (6775 2225);
FORCEPROP 1 LAST OFFPAGE TRUE
J 0
(7100 2100);
DISPLAY 0.872340 (7100 2100);
PAINT GREEN (7100 2100);
DISPLAY INVISIBLE (7100 2100);
FORCEPROP 1 LAST COMMENT_BODY TRUE
J 0
(6730 2130);
DISPLAY 0.872340 (6730 2130);
PAINT GREEN (6730 2130);
DISPLAY INVISIBLE (6730 2130);
FORCEPROP 2 LAST PATH I127
J 0
(6950 2300);
DISPLAY 1.021277 (6950 2300);
DISPLAY INVISIBLE (6950 2300);
FORCEADD OFFPAGE..2
(6800 3825);
FORCEPROP 2 LAST $XR1 165 
J 0
(7109 3825);
DISPLAY 0.638298 (7109 3825);
PAINT MONO (7109 3825);
FORCEPROP 2 LAST $XR0 162 
J 0
(6989 3825);
DISPLAY 0.638298 (6989 3825);
PAINT MONO (6989 3825);
FORCEPROP 2 LAST CDS_LIB standard
J 0
(6800 3825);
DISPLAY INVISIBLE (6800 3825);
FORCEPROP 1 LAST OFFPAGE TRUE
J 0
(7125 3700);
DISPLAY 0.872340 (7125 3700);
PAINT GREEN (7125 3700);
DISPLAY INVISIBLE (7125 3700);
FORCEPROP 1 LAST COMMENT_BODY TRUE
J 0
(6755 3730);
DISPLAY 0.872340 (6755 3730);
PAINT GREEN (6755 3730);
DISPLAY INVISIBLE (6755 3730);
FORCEPROP 2 LAST PATH I128
J 0
(6975 3900);
DISPLAY 1.021277 (6975 3900);
DISPLAY INVISIBLE (6975 3900);
FORCEADD OFFPAGE..1
(2525 4975);
FORCEPROP 2 LAST $XR1 213 
J 0
(2153 4975);
DISPLAY 0.638298 (2153 4975);
PAINT MONO (2153 4975);
FORCEPROP 2 LAST $XR0 159 
J 0
(2273 4975);
DISPLAY 0.638298 (2273 4975);
PAINT MONO (2273 4975);
FORCEPROP 2 LAST CDS_LIB standard
J 0
(2525 4975);
PAINT MONO (2525 4975);
DISPLAY INVISIBLE (2525 4975);
FORCEPROP 1 LAST OFFPAGE TRUE
J 0
(2850 4850);
DISPLAY 0.872340 (2850 4850);
PAINT GREEN (2850 4850);
DISPLAY INVISIBLE (2850 4850);
FORCEPROP 1 LAST COMMENT_BODY TRUE
J 0
(2650 4875);
DISPLAY 0.872340 (2650 4875);
PAINT GREEN (2650 4875);
DISPLAY INVISIBLE (2650 4875);
FORCEPROP 2 LAST PATH I13
J 0
(2275 5025);
DISPLAY 1.021277 (2275 5025);
DISPLAY INVISIBLE (2275 5025);
FORCEADD OFFPAGE..4
(6275 4825);
FORCEPROP 2 LAST $XR0 160 
J 0
(6461 4825);
DISPLAY 0.638298 (6461 4825);
PAINT MONO (6461 4825);
FORCEPROP 2 LAST CDS_LIB standard
J 0
(6275 4825);
PAINT MONO (6275 4825);
DISPLAY INVISIBLE (6275 4825);
FORCEPROP 1 LAST OFFPAGE TRUE
J 0
(6600 4700);
DISPLAY 0.872340 (6600 4700);
PAINT GREEN (6600 4700);
DISPLAY INVISIBLE (6600 4700);
FORCEPROP 1 LAST COMMENT_BODY TRUE
J 0
(6250 4725);
DISPLAY 0.872340 (6250 4725);
PAINT GREEN (6250 4725);
DISPLAY INVISIBLE (6250 4725);
FORCEPROP 2 LAST PATH I134
J 0
(6475 4875);
DISPLAY 1.021277 (6475 4875);
DISPLAY INVISIBLE (6475 4875);
FORCEADD OFFPAGE..4
(6275 4775);
FORCEPROP 2 LAST $XR0 160 
J 0
(6461 4775);
DISPLAY 0.638298 (6461 4775);
PAINT MONO (6461 4775);
FORCEPROP 2 LAST CDS_LIB standard
J 0
(6275 4775);
PAINT MONO (6275 4775);
DISPLAY INVISIBLE (6275 4775);
FORCEPROP 1 LAST OFFPAGE TRUE
J 0
(6600 4650);
DISPLAY 0.872340 (6600 4650);
PAINT GREEN (6600 4650);
DISPLAY INVISIBLE (6600 4650);
FORCEPROP 1 LAST COMMENT_BODY TRUE
J 0
(6250 4675);
DISPLAY 0.872340 (6250 4675);
PAINT GREEN (6250 4675);
DISPLAY INVISIBLE (6250 4675);
FORCEPROP 2 LAST PATH I135
J 0
(6475 4825);
DISPLAY 1.021277 (6475 4825);
DISPLAY INVISIBLE (6475 4825);
FORCEADD OFFPAGE..4
(6275 4875);
FORCEPROP 2 LAST $XR0 160 
J 0
(6461 4875);
DISPLAY 0.638298 (6461 4875);
PAINT MONO (6461 4875);
FORCEPROP 2 LAST CDS_LIB standard
J 0
(6275 4875);
PAINT MONO (6275 4875);
DISPLAY INVISIBLE (6275 4875);
FORCEPROP 1 LAST OFFPAGE TRUE
J 0
(6600 4750);
DISPLAY 0.872340 (6600 4750);
PAINT GREEN (6600 4750);
DISPLAY INVISIBLE (6600 4750);
FORCEPROP 1 LAST COMMENT_BODY TRUE
J 0
(6250 4775);
DISPLAY 0.872340 (6250 4775);
PAINT GREEN (6250 4775);
DISPLAY INVISIBLE (6250 4775);
FORCEPROP 2 LAST PATH I136
J 0
(6475 4925);
DISPLAY 1.021277 (6475 4925);
DISPLAY INVISIBLE (6475 4925);
FORCEADD OFFPAGE..4
(6275 4925);
FORCEPROP 2 LAST $XR0 159 
J 0
(6461 4925);
DISPLAY 0.638298 (6461 4925);
PAINT MONO (6461 4925);
FORCEPROP 2 LAST CDS_LIB standard
J 0
(6275 4925);
PAINT MONO (6275 4925);
DISPLAY INVISIBLE (6275 4925);
FORCEPROP 1 LAST OFFPAGE TRUE
J 0
(6600 4800);
DISPLAY 0.872340 (6600 4800);
PAINT GREEN (6600 4800);
DISPLAY INVISIBLE (6600 4800);
FORCEPROP 1 LAST COMMENT_BODY TRUE
J 0
(6250 4825);
DISPLAY 0.872340 (6250 4825);
PAINT GREEN (6250 4825);
DISPLAY INVISIBLE (6250 4825);
FORCEPROP 2 LAST PATH I137
J 0
(6475 4975);
DISPLAY 1.021277 (6475 4975);
DISPLAY INVISIBLE (6475 4975);
FORCEADD OFFPAGE..4
(6275 4975);
FORCEPROP 2 LAST $XR0 160 
J 0
(6461 4975);
DISPLAY 0.638298 (6461 4975);
PAINT MONO (6461 4975);
FORCEPROP 2 LAST CDS_LIB standard
J 0
(6275 4975);
DISPLAY INVISIBLE (6275 4975);
FORCEPROP 1 LAST OFFPAGE TRUE
J 0
(6600 4850);
DISPLAY 0.872340 (6600 4850);
PAINT GREEN (6600 4850);
DISPLAY INVISIBLE (6600 4850);
FORCEPROP 1 LAST COMMENT_BODY TRUE
J 0
(6250 4875);
DISPLAY 0.872340 (6250 4875);
PAINT GREEN (6250 4875);
DISPLAY INVISIBLE (6250 4875);
FORCEPROP 2 LAST PATH I138
J 0
(6475 5025);
DISPLAY 1.021277 (6475 5025);
DISPLAY INVISIBLE (6475 5025);
FORCEADD OFFPAGE..2
(6275 5025);
FORCEPROP 2 LAST $XR0 160 
J 0
(6464 5025);
DISPLAY 0.638298 (6464 5025);
PAINT MONO (6464 5025);
FORCEPROP 2 LAST CDS_LIB standard
J 0
(6275 5025);
DISPLAY INVISIBLE (6275 5025);
FORCEPROP 1 LAST OFFPAGE TRUE
J 0
(6600 4900);
DISPLAY 0.872340 (6600 4900);
PAINT GREEN (6600 4900);
DISPLAY INVISIBLE (6600 4900);
FORCEPROP 1 LAST COMMENT_BODY TRUE
J 0
(6230 4930);
DISPLAY 0.872340 (6230 4930);
PAINT GREEN (6230 4930);
DISPLAY INVISIBLE (6230 4930);
FORCEPROP 2 LAST PATH I139
J 0
(6475 5075);
DISPLAY 1.021277 (6475 5075);
DISPLAY INVISIBLE (6475 5075);
FORCEADD OFFPAGE..1
(2525 5075);
FORCEPROP 2 LAST $XR1 213 
J 0
(2153 5075);
DISPLAY 0.638298 (2153 5075);
PAINT MONO (2153 5075);
FORCEPROP 2 LAST $XR0 159 
J 0
(2273 5075);
DISPLAY 0.638298 (2273 5075);
PAINT MONO (2273 5075);
FORCEPROP 2 LAST CDS_LIB standard
J 0
(2525 5075);
PAINT MONO (2525 5075);
DISPLAY INVISIBLE (2525 5075);
FORCEPROP 1 LAST OFFPAGE TRUE
J 0
(2850 4950);
DISPLAY 0.872340 (2850 4950);
PAINT GREEN (2850 4950);
DISPLAY INVISIBLE (2850 4950);
FORCEPROP 1 LAST COMMENT_BODY TRUE
J 0
(2650 4975);
DISPLAY 0.872340 (2650 4975);
PAINT GREEN (2650 4975);
DISPLAY INVISIBLE (2650 4975);
FORCEPROP 2 LAST PATH I14
J 0
(2275 5125);
DISPLAY 1.021277 (2275 5125);
DISPLAY INVISIBLE (2275 5125);
FORCEADD OFFPAGE..4
(6275 5175);
FORCEPROP 2 LAST $XR0 161 
J 0
(6461 5175);
DISPLAY 0.638298 (6461 5175);
PAINT MONO (6461 5175);
FORCEPROP 2 LAST CDS_LIB standard
J 0
(6275 5175);
PAINT MONO (6275 5175);
DISPLAY INVISIBLE (6275 5175);
FORCEPROP 1 LAST OFFPAGE TRUE
J 0
(6600 5050);
DISPLAY 0.872340 (6600 5050);
PAINT GREEN (6600 5050);
DISPLAY INVISIBLE (6600 5050);
FORCEPROP 1 LAST COMMENT_BODY TRUE
J 0
(6250 5075);
DISPLAY 0.872340 (6250 5075);
PAINT GREEN (6250 5075);
DISPLAY INVISIBLE (6250 5075);
FORCEPROP 2 LAST PATH I140
J 0
(6475 5225);
DISPLAY 1.021277 (6475 5225);
DISPLAY INVISIBLE (6475 5225);
FORCEADD OFFPAGE..2
(6275 5075);
FORCEPROP 2 LAST $XR0 161 
J 0
(6464 5075);
DISPLAY 0.638298 (6464 5075);
PAINT MONO (6464 5075);
FORCEPROP 2 LAST CDS_LIB standard
J 0
(6275 5075);
PAINT MONO (6275 5075);
DISPLAY INVISIBLE (6275 5075);
FORCEPROP 1 LAST OFFPAGE TRUE
J 0
(6600 4950);
DISPLAY 0.872340 (6600 4950);
PAINT GREEN (6600 4950);
DISPLAY INVISIBLE (6600 4950);
FORCEPROP 1 LAST COMMENT_BODY TRUE
J 0
(6230 4980);
DISPLAY 0.872340 (6230 4980);
PAINT GREEN (6230 4980);
DISPLAY INVISIBLE (6230 4980);
FORCEPROP 2 LAST PATH I141
J 0
(6475 5125);
DISPLAY 1.021277 (6475 5125);
DISPLAY INVISIBLE (6475 5125);
FORCEADD OFFPAGE..4
(6275 5125);
FORCEPROP 2 LAST $XR0 161 
J 0
(6461 5125);
DISPLAY 0.638298 (6461 5125);
PAINT MONO (6461 5125);
FORCEPROP 2 LAST CDS_LIB standard
J 0
(6275 5125);
PAINT MONO (6275 5125);
DISPLAY INVISIBLE (6275 5125);
FORCEPROP 1 LAST OFFPAGE TRUE
J 0
(6600 5000);
DISPLAY 0.872340 (6600 5000);
PAINT GREEN (6600 5000);
DISPLAY INVISIBLE (6600 5000);
FORCEPROP 1 LAST COMMENT_BODY TRUE
J 0
(6250 5025);
DISPLAY 0.872340 (6250 5025);
PAINT GREEN (6250 5025);
DISPLAY INVISIBLE (6250 5025);
FORCEPROP 2 LAST PATH I142
J 0
(6475 5175);
DISPLAY 1.021277 (6475 5175);
DISPLAY INVISIBLE (6475 5175);
FORCEADD OFFPAGE..4
(6800 3875);
FORCEPROP 2 LAST $XR0 161 
J 0
(6986 3875);
DISPLAY 0.638298 (6986 3875);
PAINT MONO (6986 3875);
FORCEPROP 2 LAST CDS_LIB standard
J 0
(6800 3875);
PAINT MONO (6800 3875);
DISPLAY INVISIBLE (6800 3875);
FORCEPROP 1 LAST OFFPAGE TRUE
J 0
(7125 3750);
DISPLAY 0.872340 (7125 3750);
PAINT GREEN (7125 3750);
DISPLAY INVISIBLE (7125 3750);
FORCEPROP 1 LAST COMMENT_BODY TRUE
J 0
(6775 3775);
DISPLAY 0.872340 (6775 3775);
PAINT GREEN (6775 3775);
DISPLAY INVISIBLE (6775 3775);
FORCEPROP 2 LAST PATH I143
J 0
(7000 3925);
DISPLAY 1.021277 (7000 3925);
DISPLAY INVISIBLE (7000 3925);
FORCEADD UNIVERSAL_GND..1
(3675 225);
FORCEPROP 3 LASTPIN (3675 275) SIG_NAME GND\g
J 0
(3685 285);
DISPLAY 0.659574 (3685 285);
PAINT MONO (3685 285);
DISPLAY INVISIBLE (3685 285);
FORCEPROP 2 LAST CDS_LIB logical_power
J 0
(3675 225);
DISPLAY INVISIBLE (3675 225);
FORCEPROP 1 LAST HDL_POWER GND
J 1
(3700 150);
DISPLAY 0.872340 (3700 150);
PAINT GREEN (3700 150);
DISPLAY INVISIBLE (3700 150);
FORCEPROP 1 LAST PATH I144
J 0
(3750 225);
DISPLAY 0.872340 (3750 225);
PAINT AQUA (3750 225);
DISPLAY INVISIBLE (3750 225);
FORCEADD Q_RES..1
(6875 775);
FORCEPROP 1 LAST PART_NUMBER CS00002JB13
J 0
(6750 850);
DISPLAY 0.638298 (6750 850);
DISPLAY INVISIBLE (6750 850);
FORCEPROP 1 LAST VALUE 0
J 2
(7050 775);
DISPLAY 0.638298 (7050 775);
FORCEPROP 1 LAST TOLERANCE 5%
J 0
(7075 775);
DISPLAY 0.638298 (7075 775);
FORCEPROP 1 LAST PACK_TYPE 0402LF
J 0
(7150 775);
DISPLAY 0.638298 (7150 775);
FORCEPROP 1 LAST $LOCATION R3178
J 0
(6600 775);
DISPLAY 0.638298 (6600 775);
FORCEPROP 1 LASTPIN (6775 775) $PN 1
J 0
(6787 787);
DISPLAY 0.787234 (6787 787);
FORCEPROP 1 LASTPIN (6975 775) $PN 2
J 0
(6937 787);
DISPLAY 0.787234 (6937 787);
FORCEPROP 2 LAST CDS_LIB pure_quanta
J 0
(6875 775);
PAINT MONO (6875 775);
DISPLAY INVISIBLE (6875 775);
FORCEPROP 1 LAST WATTAGE 1/16W
J 2
(7050 900);
DISPLAY 0.638298 (7050 900);
DISPLAY INVISIBLE (7050 900);
FORCEPROP 1 LAST MATERIAL CHIP
J 0
(6750 900);
DISPLAY 0.638298 (6750 900);
DISPLAY INVISIBLE (6750 900);
FORCEPROP 1 LAST PATH I147
J 0
(6825 925);
DISPLAY 0.978723 (6825 925);
PAINT WHITE (6825 925);
DISPLAY INVISIBLE (6825 925);
FORCEPROP 2 LAST CDS_LOCATION R3178
J 0
(6825 975);
DISPLAY 1.021277 (6825 975);
DISPLAY INVISIBLE (6825 975);
FORCEPROP 2 LAST $SEC 1
J 0
(6825 975);
DISPLAY 0.680851 (6825 975);
PAINT MONO (6825 975);
DISPLAY INVISIBLE (6825 975);
FORCEPROP 2 LAST CDS_SEC 1
J 0
(6825 975);
DISPLAY 1.021277 (6825 975);
DISPLAY INVISIBLE (6825 975);
FORCEADD Q_RES..1
(6875 825);
FORCEPROP 1 LAST PART_NUMBER CS00002JB13
J 0
(6750 900);
DISPLAY 0.638298 (6750 900);
DISPLAY INVISIBLE (6750 900);
FORCEPROP 1 LAST WATTAGE 1/16W
J 2
(7050 950);
DISPLAY 0.638298 (7050 950);
FORCEPROP 1 LAST TOLERANCE 5%
J 0
(7075 825);
DISPLAY 0.638298 (7075 825);
FORCEPROP 1 LAST VALUE 0
J 2
(7050 825);
DISPLAY 0.638298 (7050 825);
FORCEPROP 1 LAST PACK_TYPE 0402LF
J 0
(7150 825);
DISPLAY 0.638298 (7150 825);
FORCEPROP 1 LAST MATERIAL CHIP
J 0
(6750 950);
DISPLAY 0.638298 (6750 950);
FORCEPROP 1 LAST $LOCATION R3177
J 0
(6600 825);
DISPLAY 0.638298 (6600 825);
FORCEPROP 1 LASTPIN (6775 825) $PN 1
J 0
(6787 837);
DISPLAY 0.787234 (6787 837);
FORCEPROP 1 LASTPIN (6975 825) $PN 2
J 0
(6937 837);
DISPLAY 0.787234 (6937 837);
FORCEPROP 2 LAST CDS_LIB pure_quanta
J 0
(6875 825);
PAINT MONO (6875 825);
DISPLAY INVISIBLE (6875 825);
FORCEPROP 1 LAST PATH I148
J 0
(6825 975);
DISPLAY 0.978723 (6825 975);
PAINT WHITE (6825 975);
DISPLAY INVISIBLE (6825 975);
FORCEPROP 2 LAST CDS_LOCATION R3177
J 0
(6825 1025);
DISPLAY 1.021277 (6825 1025);
DISPLAY INVISIBLE (6825 1025);
FORCEPROP 2 LAST $SEC 1
J 0
(6825 1025);
DISPLAY 0.680851 (6825 1025);
PAINT MONO (6825 1025);
DISPLAY INVISIBLE (6825 1025);
FORCEPROP 2 LAST CDS_SEC 1
J 0
(6825 1025);
DISPLAY 1.021277 (6825 1025);
DISPLAY INVISIBLE (6825 1025);
FORCEADD OFFPAGE..4
(8350 775);
FORCEPROP 2 LAST $XR0 180 
J 0
(8536 775);
DISPLAY 0.638298 (8536 775);
PAINT MONO (8536 775);
FORCEPROP 2 LAST CDS_LIB standard
J 0
(8350 775);
PAINT MONO (8350 775);
DISPLAY INVISIBLE (8350 775);
FORCEPROP 1 LAST OFFPAGE TRUE
J 0
(8675 650);
DISPLAY 0.872340 (8675 650);
PAINT GREEN (8675 650);
DISPLAY INVISIBLE (8675 650);
FORCEPROP 1 LAST COMMENT_BODY TRUE
J 0
(8325 675);
DISPLAY 0.872340 (8325 675);
PAINT GREEN (8325 675);
DISPLAY INVISIBLE (8325 675);
FORCEPROP 2 LAST PATH I149
J 0
(8550 825);
DISPLAY 1.021277 (8550 825);
DISPLAY INVISIBLE (8550 825);
FORCEADD OFFPAGE..1
(2525 5025);
FORCEPROP 2 LAST $XR1 213 
J 0
(2153 5025);
DISPLAY 0.638298 (2153 5025);
PAINT MONO (2153 5025);
FORCEPROP 2 LAST $XR0 159 
J 0
(2273 5025);
DISPLAY 0.638298 (2273 5025);
PAINT MONO (2273 5025);
FORCEPROP 2 LAST CDS_LIB standard
J 0
(2525 5025);
PAINT MONO (2525 5025);
DISPLAY INVISIBLE (2525 5025);
FORCEPROP 1 LAST OFFPAGE TRUE
J 0
(2850 4900);
DISPLAY 0.872340 (2850 4900);
PAINT GREEN (2850 4900);
DISPLAY INVISIBLE (2850 4900);
FORCEPROP 1 LAST COMMENT_BODY TRUE
J 0
(2650 4925);
DISPLAY 0.872340 (2650 4925);
PAINT GREEN (2650 4925);
DISPLAY INVISIBLE (2650 4925);
FORCEPROP 2 LAST PATH I15
J 0
(2275 5075);
DISPLAY 1.021277 (2275 5075);
DISPLAY INVISIBLE (2275 5075);
FORCEADD OFFPAGE..4
(8350 825);
FORCEPROP 2 LAST $XR0 180 
J 0
(8536 825);
DISPLAY 0.638298 (8536 825);
PAINT MONO (8536 825);
FORCEPROP 2 LAST CDS_LIB standard
J 0
(8350 825);
PAINT MONO (8350 825);
DISPLAY INVISIBLE (8350 825);
FORCEPROP 1 LAST OFFPAGE TRUE
J 0
(8675 700);
DISPLAY 0.872340 (8675 700);
PAINT GREEN (8675 700);
DISPLAY INVISIBLE (8675 700);
FORCEPROP 1 LAST COMMENT_BODY TRUE
J 0
(8325 725);
DISPLAY 0.872340 (8325 725);
PAINT GREEN (8325 725);
DISPLAY INVISIBLE (8325 725);
FORCEPROP 2 LAST PATH I150
J 0
(8550 875);
DISPLAY 1.021277 (8550 875);
DISPLAY INVISIBLE (8550 875);
FORCEADD UNIVERSAL_GND..1
(7975 3400);
FORCEPROP 3 LASTPIN (7975 3450) SIG_NAME GND\g
J 0
(7985 3460);
DISPLAY 0.659574 (7985 3460);
PAINT MONO (7985 3460);
DISPLAY INVISIBLE (7985 3460);
FORCEPROP 2 LAST CDS_LIB logical_power
J 0
(7975 3400);
DISPLAY INVISIBLE (7975 3400);
FORCEPROP 1 LAST HDL_POWER GND
J 1
(8000 3325);
DISPLAY 0.872340 (8000 3325);
PAINT GREEN (8000 3325);
DISPLAY INVISIBLE (8000 3325);
FORCEPROP 1 LAST PATH I151
J 0
(8050 3400);
DISPLAY 0.872340 (8050 3400);
PAINT AQUA (8050 3400);
DISPLAY INVISIBLE (8050 3400);
FORCEPROP 2 LAST ROOM IO_SLOT
J 1
(7750 3475);
DISPLAY 0.744681 (7750 3475);
DISPLAY INVISIBLE (7750 3475);
FORCEADD Q_RES..2
(7975 3675);
FORCEPROP 1 LAST PART_NUMBER CS11002FB07
J 0
(8015 3550);
DISPLAY 0.638298 (8015 3550);
DISPLAY INVISIBLE (8015 3550);
FORCEPROP 1 LAST PACK_TYPE 0402LF
J 0
(8015 3500);
DISPLAY 0.638298 (8015 3500);
FORCEPROP 1 LAST MATERIAL CHIP
J 0
(8015 3600);
DISPLAY 0.638298 (8015 3600);
FORCEPROP 1 LAST VALUE 100
J 0
(8020 3750);
DISPLAY 0.638298 (8020 3750);
FORCEPROP 1 LAST WATTAGE 1/16W
J 0
(8015 3650);
DISPLAY 0.638298 (8015 3650);
FORCEPROP 1 LAST TOLERANCE 1%
J 0
(8020 3700);
DISPLAY 0.638298 (8020 3700);
FORCEPROP 1 LAST $LOCATION R3180
J 0
(8020 3800);
DISPLAY 0.638298 (8020 3800);
FORCEPROP 1 LASTPIN (7975 3775) $PN 1
J 0
(7980 3737);
DISPLAY 0.787234 (7980 3737);
PAINT MONO (7980 3737);
FORCEPROP 1 LASTPIN (7975 3575) $PN 2
J 0
(7980 3585);
DISPLAY 0.787234 (7980 3585);
PAINT MONO (7980 3585);
FORCEPROP 2 LAST CDS_LIB pure_quanta
J 0
(7975 3675);
DISPLAY INVISIBLE (7975 3675);
FORCEPROP 1 LAST PATH I152
J 0
(8025 3850);
DISPLAY 0.978723 (8025 3850);
PAINT WHITE (8025 3850);
DISPLAY INVISIBLE (8025 3850);
FORCEPROP 0 LAST CDS_LOCATION R3180
J 0
(8025 3850);
DISPLAY 1.021277 (8025 3850);
DISPLAY INVISIBLE (8025 3850);
FORCEPROP 0 LAST $SEC 1
J 0
(8025 3850);
DISPLAY 0.680851 (8025 3850);
PAINT MONO (8025 3850);
DISPLAY INVISIBLE (8025 3850);
FORCEPROP 0 LAST CDS_SEC 1
J 0
(8025 3850);
DISPLAY 1.021277 (8025 3850);
DISPLAY INVISIBLE (8025 3850);
FORCEADD OFFPAGE..4
(6450 725);
FORCEPROP 2 LAST $XR0 161 
J 0
(6636 725);
DISPLAY 0.638298 (6636 725);
PAINT MONO (6636 725);
FORCEPROP 2 LAST CDS_LIB standard
J 0
(6450 725);
PAINT MONO (6450 725);
DISPLAY INVISIBLE (6450 725);
FORCEPROP 1 LAST OFFPAGE TRUE
J 0
(6775 600);
DISPLAY 0.872340 (6775 600);
PAINT GREEN (6775 600);
DISPLAY INVISIBLE (6775 600);
FORCEPROP 1 LAST COMMENT_BODY TRUE
J 0
(6425 625);
DISPLAY 0.872340 (6425 625);
PAINT GREEN (6425 625);
DISPLAY INVISIBLE (6425 625);
FORCEPROP 2 LAST PATH I153
J 0
(6650 775);
DISPLAY 1.021277 (6650 775);
DISPLAY INVISIBLE (6650 775);
FORCEADD OFFPAGE..5
(2425 -575);
FORCEPROP 2 LAST $XR1 159 
J 0
(2020 -575);
DISPLAY 0.638298 (2020 -575);
PAINT MONO (2020 -575);
FORCEPROP 2 LAST $XR0 213 
J 0
(2140 -575);
DISPLAY 0.638298 (2140 -575);
PAINT MONO (2140 -575);
FORCEPROP 2 LAST CDS_LIB standard
J 0
(2425 -575);
PAINT MONO (2425 -575);
DISPLAY INVISIBLE (2425 -575);
FORCEPROP 1 LAST OFFPAGE TRUE
J 0
(2750 -700);
DISPLAY 0.872340 (2750 -700);
PAINT GREEN (2750 -700);
DISPLAY INVISIBLE (2750 -700);
FORCEPROP 1 LAST COMMENT_BODY TRUE
J 0
(2525 -650);
DISPLAY 0.872340 (2525 -650);
PAINT GREEN (2525 -650);
DISPLAY INVISIBLE (2525 -650);
FORCEPROP 2 LAST PATH I156
J 0
(2150 -525);
DISPLAY 1.021277 (2150 -525);
DISPLAY INVISIBLE (2150 -525);
FORCEADD OFFPAGE..5
(2425 -225);
FORCEPROP 2 LAST $XR1 213 
J 0
(2020 -225);
DISPLAY 0.638298 (2020 -225);
PAINT MONO (2020 -225);
FORCEPROP 2 LAST $XR0 159 
J 0
(2140 -225);
DISPLAY 0.638298 (2140 -225);
PAINT MONO (2140 -225);
FORCEPROP 2 LAST CDS_LIB standard
J 0
(2425 -225);
PAINT MONO (2425 -225);
DISPLAY INVISIBLE (2425 -225);
FORCEPROP 1 LAST OFFPAGE TRUE
J 0
(2750 -350);
DISPLAY 0.872340 (2750 -350);
PAINT GREEN (2750 -350);
DISPLAY INVISIBLE (2750 -350);
FORCEPROP 1 LAST COMMENT_BODY TRUE
J 0
(2525 -300);
DISPLAY 0.872340 (2525 -300);
PAINT GREEN (2525 -300);
DISPLAY INVISIBLE (2525 -300);
FORCEPROP 2 LAST PATH I158
J 0
(2150 -175);
DISPLAY 1.021277 (2150 -175);
DISPLAY INVISIBLE (2150 -175);
FORCEADD OFFPAGE..5
(2425 -50);
FORCEPROP 2 LAST $XR1 159 
J 0
(2020 -50);
DISPLAY 0.638298 (2020 -50);
PAINT MONO (2020 -50);
FORCEPROP 2 LAST $XR0 213 
J 0
(2140 -50);
DISPLAY 0.638298 (2140 -50);
PAINT MONO (2140 -50);
FORCEPROP 2 LAST CDS_LIB standard
J 0
(2425 -50);
PAINT MONO (2425 -50);
DISPLAY INVISIBLE (2425 -50);
FORCEPROP 1 LAST OFFPAGE TRUE
J 0
(2750 -175);
DISPLAY 0.872340 (2750 -175);
PAINT GREEN (2750 -175);
DISPLAY INVISIBLE (2750 -175);
FORCEPROP 1 LAST COMMENT_BODY TRUE
J 0
(2525 -125);
DISPLAY 0.872340 (2525 -125);
PAINT GREEN (2525 -125);
DISPLAY INVISIBLE (2525 -125);
FORCEPROP 2 LAST PATH I159
J 0
(2150 0);
DISPLAY 1.021277 (2150 0);
DISPLAY INVISIBLE (2150 0);
FORCEADD UNIVERSAL_GND..1
(300 -400);
FORCEPROP 3 LASTPIN (300 -350) SIG_NAME GND\g
J 0
(310 -340);
DISPLAY 0.659574 (310 -340);
PAINT MONO (310 -340);
DISPLAY INVISIBLE (310 -340);
FORCEPROP 2 LAST CDS_LIB logical_power
J 0
(300 -400);
PAINT MONO (300 -400);
DISPLAY INVISIBLE (300 -400);
FORCEPROP 1 LAST HDL_POWER GND
J 1
(325 -475);
DISPLAY 0.872340 (325 -475);
PAINT GREEN (325 -475);
DISPLAY INVISIBLE (325 -475);
FORCEPROP 1 LAST PATH I16
J 0
(375 -400);
DISPLAY 0.872340 (375 -400);
PAINT AQUA (375 -400);
DISPLAY INVISIBLE (375 -400);
FORCEPROP 2 LAST ROOM IO_SLOT
J 1
(75 -325);
DISPLAY 0.744681 (75 -325);
DISPLAY INVISIBLE (75 -325);
FORCEADD UNIVERSAL_GND..1
(4225 -700);
FORCEPROP 3 LASTPIN (4225 -650) SIG_NAME GND\g
J 0
(4235 -640);
DISPLAY 0.659574 (4235 -640);
PAINT MONO (4235 -640);
DISPLAY INVISIBLE (4235 -640);
FORCEPROP 2 LAST CDS_LIB logical_power
J 0
(4225 -700);
PAINT MONO (4225 -700);
DISPLAY INVISIBLE (4225 -700);
FORCEPROP 1 LAST HDL_POWER GND
J 1
(4250 -775);
DISPLAY 0.872340 (4250 -775);
PAINT GREEN (4250 -775);
DISPLAY INVISIBLE (4250 -775);
FORCEPROP 1 LAST PATH I163
J 0
(4300 -700);
DISPLAY 0.872340 (4300 -700);
PAINT AQUA (4300 -700);
DISPLAY INVISIBLE (4300 -700);
FORCEPROP 2 LAST ROOM IO_SLOT
J 1
(4000 -625);
DISPLAY 0.744681 (4000 -625);
DISPLAY INVISIBLE (4000 -625);
FORCEADD UNIVERSAL_POWER..1
(4225 100);
FORCEPROP 3 LASTPIN (4225 50) SIG_NAME P3V3_OCP_V3_2\g
J 0
(4235 60);
DISPLAY 0.659574 (4235 60);
PAINT MONO (4235 60);
DISPLAY INVISIBLE (4235 60);
FORCEPROP 1 LAST HDL_POWER P3V3_OCP_V3_2
J 1
(4225 150);
DISPLAY 0.872340 (4225 150);
PAINT GREEN (4225 150);
FORCEPROP 2 LAST CDS_LIB logical_power
J 0
(4225 100);
PAINT MONO (4225 100);
DISPLAY INVISIBLE (4225 100);
FORCEPROP 1 LAST PATH I164
J 0
(4275 125);
DISPLAY 0.872340 (4275 125);
PAINT AQUA (4275 125);
DISPLAY INVISIBLE (4275 125);
FORCEADD Q_RES..1
(3675 -50);
FORCEPROP 1 LAST PART_NUMBER CS21002FB06
J 0
(3625 0);
DISPLAY 0.510638 (3625 0);
DISPLAY INVISIBLE (3625 0);
FORCEPROP 1 LAST TOLERANCE 1%
J 0
(3925 -50);
DISPLAY 0.638298 (3925 -50);
FORCEPROP 1 LAST MATERIAL CHIP
J 0
(4050 -50);
DISPLAY 0.638298 (4050 -50);
FORCEPROP 1 LAST VALUE 1K
J 2
(3875 -50);
DISPLAY 0.638298 (3875 -50);
FORCEPROP 1 LAST PACK_TYPE 0402LF
J 0
(3625 50);
DISPLAY 0.510638 (3625 50);
FORCEPROP 1 LAST WATTAGE 1/16W
J 2
(3925 50);
DISPLAY 0.510638 (3925 50);
FORCEPROP 1 LAST $LOCATION R3173
J 0
(3450 -50);
DISPLAY 0.787234 (3450 -50);
FORCEPROP 1 LASTPIN (3575 -50) $PN 1
J 0
(3587 -38);
DISPLAY 0.787234 (3587 -38);
FORCEPROP 1 LASTPIN (3775 -50) $PN 2
J 0
(3737 -38);
DISPLAY 0.787234 (3737 -38);
FORCEPROP 2 LAST CDS_LIB pure_quanta
J 0
(3675 -50);
PAINT MONO (3675 -50);
DISPLAY INVISIBLE (3675 -50);
FORCEPROP 1 LAST PATH I165
J 0
(3625 100);
DISPLAY 0.978723 (3625 100);
PAINT WHITE (3625 100);
DISPLAY INVISIBLE (3625 100);
FORCEPROP 2 LAST CDS_LOCATION R3173
J 0
(3625 150);
DISPLAY 1.021277 (3625 150);
DISPLAY INVISIBLE (3625 150);
FORCEPROP 2 LAST $SEC 1
J 0
(3625 150);
DISPLAY 0.680851 (3625 150);
PAINT MONO (3625 150);
DISPLAY INVISIBLE (3625 150);
FORCEPROP 2 LAST CDS_SEC 1
J 0
(3625 150);
DISPLAY 1.021277 (3625 150);
DISPLAY INVISIBLE (3625 150);
FORCEADD Q_CAP..1
(5725 -250);
FORCEPROP 1 LAST PART_NUMBER CH6223MEA00
J 0
(5775 -450);
DISPLAY 0.808511 (5775 -450);
DISPLAY INVISIBLE (5775 -450);
FORCEPROP 1 LAST VALUE 22UF
J 0
(5775 -200);
DISPLAY 0.638298 (5775 -200);
FORCEPROP 1 LAST MATERIAL X6S
J 0
(5775 -350);
DISPLAY 0.638298 (5775 -350);
FORCEPROP 1 LAST TOLERANCE 20%
J 0
(5775 -300);
DISPLAY 0.638298 (5775 -300);
FORCEPROP 1 LAST VOLTAGE 16V
J 0
(5775 -250);
DISPLAY 0.638298 (5775 -250);
FORCEPROP 1 LAST PACK_TYPE C0805
J 0
(5775 -400);
DISPLAY 0.638298 (5775 -400);
FORCEPROP 1 LAST $LOCATION C1829
J 0
(5775 -150);
DISPLAY 0.787234 (5775 -150);
FORCEPROP 1 LASTPIN (5725 -150) $PN 1
J 0
(5735 -170);
DISPLAY 0.787234 (5735 -170);
FORCEPROP 1 LASTPIN (5725 -350) $PN 2
J 0
(5735 -370);
DISPLAY 0.787234 (5735 -370);
FORCEPROP 2 LAST CDS_LIB pure_quanta
J 0
(5725 -250);
PAINT MONO (5725 -250);
DISPLAY INVISIBLE (5725 -250);
FORCEPROP 1 LAST PATH I166
J 0
(5775 -100);
DISPLAY 0.978723 (5775 -100);
PAINT WHITE (5775 -100);
DISPLAY INVISIBLE (5775 -100);
FORCEPROP 2 LAST CDS_LOCATION C1829
J 0
(5775 -50);
DISPLAY 1.021277 (5775 -50);
DISPLAY INVISIBLE (5775 -50);
FORCEPROP 2 LAST $SEC 1
J 0
(5775 -50);
DISPLAY 0.680851 (5775 -50);
PAINT MONO (5775 -50);
DISPLAY INVISIBLE (5775 -50);
FORCEPROP 2 LAST CDS_SEC 1
J 0
(5775 -50);
DISPLAY 1.021277 (5775 -50);
DISPLAY INVISIBLE (5775 -50);
FORCEADD Q_CAP..1
(6000 -250);
FORCEPROP 1 LAST PART_NUMBER CH6223MEA00
J 0
(6050 -400);
DISPLAY 0.638298 (6050 -400);
DISPLAY INVISIBLE (6050 -400);
FORCEPROP 1 LAST PACK_TYPE C0805
J 0
(6050 -450);
DISPLAY 0.638298 (6050 -450);
FORCEPROP 1 LAST MATERIAL X6S
J 0
(6050 -350);
DISPLAY 0.638298 (6050 -350);
FORCEPROP 1 LAST TOLERANCE 20%
J 0
(6050 -300);
DISPLAY 0.638298 (6050 -300);
FORCEPROP 1 LAST VOLTAGE 16V
J 0
(6050 -250);
DISPLAY 0.638298 (6050 -250);
FORCEPROP 1 LAST VALUE 22UF
J 0
(6050 -200);
DISPLAY 0.638298 (6050 -200);
FORCEPROP 1 LAST $LOCATION C1830
J 0
(6050 -150);
DISPLAY 0.787234 (6050 -150);
FORCEPROP 1 LASTPIN (6000 -150) $PN 1
J 0
(6010 -170);
DISPLAY 0.787234 (6010 -170);
FORCEPROP 1 LASTPIN (6000 -350) $PN 2
J 0
(6010 -370);
DISPLAY 0.787234 (6010 -370);
FORCEPROP 2 LAST CDS_LIB pure_quanta
J 0
(6000 -250);
PAINT MONO (6000 -250);
DISPLAY INVISIBLE (6000 -250);
FORCEPROP 1 LAST PATH I167
J 0
(6050 -100);
DISPLAY 0.978723 (6050 -100);
PAINT WHITE (6050 -100);
DISPLAY INVISIBLE (6050 -100);
FORCEPROP 2 LAST CDS_LOCATION C1830
J 0
(6050 -50);
DISPLAY 1.021277 (6050 -50);
DISPLAY INVISIBLE (6050 -50);
FORCEPROP 2 LAST $SEC 1
J 0
(6050 -50);
DISPLAY 0.680851 (6050 -50);
PAINT MONO (6050 -50);
DISPLAY INVISIBLE (6050 -50);
FORCEPROP 2 LAST CDS_SEC 1
J 0
(6050 -50);
DISPLAY 1.021277 (6050 -50);
DISPLAY INVISIBLE (6050 -50);
FORCEADD Q_CAP..1
(6400 -250);
FORCEPROP 1 LAST PART_NUMBER CH4104K1B00
J 0
(6450 -400);
DISPLAY 0.808511 (6450 -400);
DISPLAY INVISIBLE (6450 -400);
FORCEPROP 1 LAST PACK_TYPE 0402
J 0
(6450 -400);
DISPLAY 0.638298 (6450 -400);
FORCEPROP 1 LAST VOLTAGE 25V
J 0
(6450 -250);
DISPLAY 0.638298 (6450 -250);
FORCEPROP 1 LAST MATERIAL X7R
J 0
(6450 -350);
DISPLAY 0.638298 (6450 -350);
FORCEPROP 1 LAST TOLERANCE 10%
J 0
(6450 -300);
DISPLAY 0.638298 (6450 -300);
FORCEPROP 1 LAST VALUE 0.1UF
J 0
(6450 -200);
DISPLAY 0.638298 (6450 -200);
FORCEPROP 1 LAST $LOCATION C1831
J 0
(6450 -150);
DISPLAY 0.787234 (6450 -150);
FORCEPROP 1 LASTPIN (6400 -150) $PN 1
J 0
(6410 -170);
DISPLAY 0.787234 (6410 -170);
FORCEPROP 1 LASTPIN (6400 -350) $PN 2
J 0
(6410 -370);
DISPLAY 0.787234 (6410 -370);
FORCEPROP 2 LAST CDS_LIB pure_quanta
J 0
(6400 -250);
PAINT MONO (6400 -250);
DISPLAY INVISIBLE (6400 -250);
FORCEPROP 1 LAST PATH I168
J 0
(6450 -100);
DISPLAY 0.978723 (6450 -100);
PAINT WHITE (6450 -100);
DISPLAY INVISIBLE (6450 -100);
FORCEPROP 2 LAST CDS_LOCATION C1831
J 0
(6450 -50);
DISPLAY 1.021277 (6450 -50);
DISPLAY INVISIBLE (6450 -50);
FORCEPROP 2 LAST $SEC 1
J 0
(6450 -50);
DISPLAY 0.680851 (6450 -50);
PAINT MONO (6450 -50);
DISPLAY INVISIBLE (6450 -50);
FORCEPROP 2 LAST CDS_SEC 1
J 0
(6450 -50);
DISPLAY 1.021277 (6450 -50);
DISPLAY INVISIBLE (6450 -50);
FORCEADD Q_CAP..1
(6950 -250);
FORCEPROP 1 LAST PART_NUMBER CH4104K1B00
J 0
(7000 -400);
DISPLAY 0.808511 (7000 -400);
DISPLAY INVISIBLE (7000 -400);
FORCEPROP 1 LAST PACK_TYPE 0402
J 0
(7000 -400);
DISPLAY 0.638298 (7000 -400);
FORCEPROP 1 LAST VALUE 0.1UF
J 0
(7000 -200);
DISPLAY 0.638298 (7000 -200);
FORCEPROP 1 LAST MATERIAL X7R
J 0
(7000 -350);
DISPLAY 0.638298 (7000 -350);
FORCEPROP 1 LAST VOLTAGE 25V
J 0
(7000 -250);
DISPLAY 0.638298 (7000 -250);
FORCEPROP 1 LAST TOLERANCE 10%
J 0
(7000 -300);
DISPLAY 0.638298 (7000 -300);
FORCEPROP 1 LAST $LOCATION C1833
J 0
(7000 -150);
DISPLAY 0.787234 (7000 -150);
FORCEPROP 1 LASTPIN (6950 -150) $PN 1
J 0
(6960 -170);
DISPLAY 0.787234 (6960 -170);
FORCEPROP 1 LASTPIN (6950 -350) $PN 2
J 0
(6960 -370);
DISPLAY 0.787234 (6960 -370);
FORCEPROP 2 LAST CDS_LIB pure_quanta
J 0
(6950 -250);
PAINT MONO (6950 -250);
DISPLAY INVISIBLE (6950 -250);
FORCEPROP 1 LAST PATH I169
J 0
(7000 -100);
DISPLAY 0.978723 (7000 -100);
PAINT WHITE (7000 -100);
DISPLAY INVISIBLE (7000 -100);
FORCEPROP 2 LAST CDS_LOCATION C1833
J 0
(7000 -50);
DISPLAY 1.021277 (7000 -50);
DISPLAY INVISIBLE (7000 -50);
FORCEPROP 2 LAST $SEC 1
J 0
(7000 -50);
DISPLAY 0.680851 (7000 -50);
PAINT MONO (7000 -50);
DISPLAY INVISIBLE (7000 -50);
FORCEPROP 2 LAST CDS_SEC 1
J 0
(7000 -50);
DISPLAY 1.021277 (7000 -50);
DISPLAY INVISIBLE (7000 -50);
FORCEADD UNIVERSAL_POWER..1
(5725 100);
FORCEPROP 3 LASTPIN (5725 50) SIG_NAME P12V_OCP_V3_2\g
J 0
(5735 60);
DISPLAY 0.659574 (5735 60);
PAINT MONO (5735 60);
DISPLAY INVISIBLE (5735 60);
FORCEPROP 1 LAST HDL_POWER P12V_OCP_V3_2
J 1
(5725 150);
DISPLAY 0.872340 (5725 150);
PAINT GREEN (5725 150);
FORCEPROP 2 LAST CDS_LIB logical_power
J 0
(5725 100);
PAINT MONO (5725 100);
DISPLAY INVISIBLE (5725 100);
FORCEPROP 1 LAST PATH I170
J 0
(5775 125);
DISPLAY 0.872340 (5775 125);
PAINT AQUA (5775 125);
DISPLAY INVISIBLE (5775 125);
FORCEADD Q_CAP..1
(7425 -250);
FORCEPROP 1 LAST PART_NUMBER CH4104K1B00
J 0
(7475 -450);
DISPLAY 0.638298 (7475 -450);
DISPLAY INVISIBLE (7475 -450);
FORCEPROP 1 LAST VOLTAGE 25V
J 0
(7475 -250);
DISPLAY 0.638298 (7475 -250);
FORCEPROP 1 LAST VALUE 0.1UF
J 0
(7475 -200);
DISPLAY 0.638298 (7475 -200);
FORCEPROP 1 LAST TOLERANCE 10%
J 0
(7475 -300);
DISPLAY 0.638298 (7475 -300);
FORCEPROP 1 LAST MATERIAL X7R
J 0
(7475 -350);
DISPLAY 0.638298 (7475 -350);
FORCEPROP 1 LAST PACK_TYPE 0402
J 0
(7475 -400);
DISPLAY 0.638298 (7475 -400);
FORCEPROP 1 LAST $LOCATION C1834
J 0
(7475 -150);
DISPLAY 0.787234 (7475 -150);
FORCEPROP 1 LASTPIN (7425 -150) $PN 1
J 0
(7435 -170);
DISPLAY 0.787234 (7435 -170);
FORCEPROP 1 LASTPIN (7425 -350) $PN 2
J 0
(7435 -370);
DISPLAY 0.787234 (7435 -370);
FORCEPROP 2 LAST CDS_LIB pure_quanta
J 0
(7425 -250);
PAINT MONO (7425 -250);
DISPLAY INVISIBLE (7425 -250);
FORCEPROP 1 LAST PATH I171
J 0
(7475 -100);
DISPLAY 0.978723 (7475 -100);
PAINT WHITE (7475 -100);
DISPLAY INVISIBLE (7475 -100);
FORCEPROP 2 LAST CDS_LOCATION C1834
J 0
(7475 -50);
DISPLAY 1.021277 (7475 -50);
DISPLAY INVISIBLE (7475 -50);
FORCEPROP 2 LAST $SEC 1
J 0
(7475 -50);
DISPLAY 0.680851 (7475 -50);
PAINT MONO (7475 -50);
DISPLAY INVISIBLE (7475 -50);
FORCEPROP 2 LAST CDS_SEC 1
J 0
(7475 -50);
DISPLAY 1.021277 (7475 -50);
DISPLAY INVISIBLE (7475 -50);
FORCEADD UNIVERSAL_GND..1
(7425 -575);
FORCEPROP 3 LASTPIN (7425 -525) SIG_NAME GND\g
J 0
(7435 -515);
DISPLAY 0.659574 (7435 -515);
PAINT MONO (7435 -515);
DISPLAY INVISIBLE (7435 -515);
FORCEPROP 2 LAST CDS_LIB logical_power
J 0
(7425 -575);
PAINT MONO (7425 -575);
DISPLAY INVISIBLE (7425 -575);
FORCEPROP 1 LAST HDL_POWER GND
J 1
(7450 -650);
DISPLAY 0.872340 (7450 -650);
PAINT GREEN (7450 -650);
DISPLAY INVISIBLE (7450 -650);
FORCEPROP 1 LAST PATH I172
J 0
(7500 -575);
DISPLAY 0.872340 (7500 -575);
PAINT AQUA (7500 -575);
DISPLAY INVISIBLE (7500 -575);
FORCEPROP 2 LAST ROOM IO_SLOT
J 1
(7200 -500);
DISPLAY 0.744681 (7200 -500);
DISPLAY INVISIBLE (7200 -500);
FORCEADD Q_CAP..1
(7925 -250);
FORCEPROP 1 LAST PART_NUMBER CH4104K1B00
J 0
(7975 -400);
DISPLAY 0.808511 (7975 -400);
DISPLAY INVISIBLE (7975 -400);
FORCEPROP 1 LAST VOLTAGE 25V
J 0
(7975 -250);
DISPLAY 0.638298 (7975 -250);
FORCEPROP 1 LAST TOLERANCE 10%
J 0
(7975 -300);
DISPLAY 0.638298 (7975 -300);
FORCEPROP 1 LAST PACK_TYPE 0402
J 0
(7975 -400);
DISPLAY 0.638298 (7975 -400);
FORCEPROP 1 LAST MATERIAL X7R
J 0
(7975 -350);
DISPLAY 0.638298 (7975 -350);
FORCEPROP 1 LAST VALUE 0.1UF
J 0
(7975 -200);
DISPLAY 0.638298 (7975 -200);
FORCEPROP 1 LAST $LOCATION C1835
J 0
(7975 -150);
DISPLAY 0.787234 (7975 -150);
FORCEPROP 1 LASTPIN (7925 -150) $PN 1
J 0
(7935 -170);
DISPLAY 0.787234 (7935 -170);
FORCEPROP 1 LASTPIN (7925 -350) $PN 2
J 0
(7935 -370);
DISPLAY 0.787234 (7935 -370);
FORCEPROP 2 LAST CDS_LIB pure_quanta
J 0
(7925 -250);
PAINT MONO (7925 -250);
DISPLAY INVISIBLE (7925 -250);
FORCEPROP 1 LAST PATH I173
J 0
(7975 -100);
DISPLAY 0.978723 (7975 -100);
PAINT WHITE (7975 -100);
DISPLAY INVISIBLE (7975 -100);
FORCEPROP 2 LAST CDS_LOCATION C1835
J 0
(7975 -50);
DISPLAY 1.021277 (7975 -50);
DISPLAY INVISIBLE (7975 -50);
FORCEPROP 2 LAST $SEC 1
J 0
(7975 -50);
DISPLAY 0.680851 (7975 -50);
PAINT MONO (7975 -50);
DISPLAY INVISIBLE (7975 -50);
FORCEPROP 2 LAST CDS_SEC 1
J 0
(7975 -50);
DISPLAY 1.021277 (7975 -50);
DISPLAY INVISIBLE (7975 -50);
FORCEADD Q_CAP..1
(8175 -250);
FORCEPROP 1 LAST PART_NUMBER CH4104K1B00
J 0
(8225 -400);
DISPLAY 0.808511 (8225 -400);
DISPLAY INVISIBLE (8225 -400);
FORCEPROP 1 LAST MATERIAL X7R
J 0
(8225 -350);
DISPLAY 0.638298 (8225 -350);
FORCEPROP 1 LAST TOLERANCE 10%
J 0
(8225 -300);
DISPLAY 0.638298 (8225 -300);
FORCEPROP 1 LAST VALUE 0.1UF
J 0
(8225 -200);
DISPLAY 0.638298 (8225 -200);
FORCEPROP 1 LAST PACK_TYPE 0402
J 0
(8225 -400);
DISPLAY 0.638298 (8225 -400);
FORCEPROP 1 LAST VOLTAGE 25V
J 0
(8225 -250);
DISPLAY 0.638298 (8225 -250);
FORCEPROP 1 LAST $LOCATION C1836
J 0
(8225 -150);
DISPLAY 0.787234 (8225 -150);
FORCEPROP 1 LASTPIN (8175 -150) $PN 1
J 0
(8185 -170);
DISPLAY 0.787234 (8185 -170);
FORCEPROP 1 LASTPIN (8175 -350) $PN 2
J 0
(8185 -370);
DISPLAY 0.787234 (8185 -370);
FORCEPROP 2 LAST CDS_LIB pure_quanta
J 0
(8175 -250);
PAINT MONO (8175 -250);
DISPLAY INVISIBLE (8175 -250);
FORCEPROP 1 LAST PATH I174
J 0
(8225 -100);
DISPLAY 0.978723 (8225 -100);
PAINT WHITE (8225 -100);
DISPLAY INVISIBLE (8225 -100);
FORCEPROP 2 LAST CDS_LOCATION C1836
J 0
(8225 -50);
DISPLAY 1.021277 (8225 -50);
DISPLAY INVISIBLE (8225 -50);
FORCEPROP 2 LAST $SEC 1
J 0
(8225 -50);
DISPLAY 0.680851 (8225 -50);
PAINT MONO (8225 -50);
DISPLAY INVISIBLE (8225 -50);
FORCEPROP 2 LAST CDS_SEC 1
J 0
(8225 -50);
DISPLAY 1.021277 (8225 -50);
DISPLAY INVISIBLE (8225 -50);
FORCEADD Q_CAP..1
(8450 -250);
FORCEPROP 1 LAST PART_NUMBER CH4104K1B00
J 0
(8500 -400);
DISPLAY 0.808511 (8500 -400);
DISPLAY INVISIBLE (8500 -400);
FORCEPROP 1 LAST PACK_TYPE 0402
J 0
(8500 -400);
DISPLAY 0.638298 (8500 -400);
FORCEPROP 1 LAST MATERIAL X7R
J 0
(8500 -350);
DISPLAY 0.638298 (8500 -350);
FORCEPROP 1 LAST TOLERANCE 10%
J 0
(8500 -300);
DISPLAY 0.638298 (8500 -300);
FORCEPROP 1 LAST VOLTAGE 25V
J 0
(8500 -250);
DISPLAY 0.638298 (8500 -250);
FORCEPROP 1 LAST VALUE 0.1UF
J 0
(8500 -200);
DISPLAY 0.638298 (8500 -200);
FORCEPROP 1 LAST $LOCATION C1837
J 0
(8500 -150);
DISPLAY 0.787234 (8500 -150);
FORCEPROP 1 LASTPIN (8450 -150) $PN 1
J 0
(8460 -170);
DISPLAY 0.787234 (8460 -170);
FORCEPROP 1 LASTPIN (8450 -350) $PN 2
J 0
(8460 -370);
DISPLAY 0.787234 (8460 -370);
FORCEPROP 2 LAST CDS_LIB pure_quanta
J 0
(8450 -250);
PAINT MONO (8450 -250);
DISPLAY INVISIBLE (8450 -250);
FORCEPROP 1 LAST PATH I175
J 0
(8500 -100);
DISPLAY 0.978723 (8500 -100);
PAINT WHITE (8500 -100);
DISPLAY INVISIBLE (8500 -100);
FORCEPROP 2 LAST CDS_LOCATION C1837
J 0
(8500 -50);
DISPLAY 1.021277 (8500 -50);
DISPLAY INVISIBLE (8500 -50);
FORCEPROP 2 LAST $SEC 1
J 0
(8500 -50);
DISPLAY 0.680851 (8500 -50);
PAINT MONO (8500 -50);
DISPLAY INVISIBLE (8500 -50);
FORCEPROP 2 LAST CDS_SEC 1
J 0
(8500 -50);
DISPLAY 1.021277 (8500 -50);
DISPLAY INVISIBLE (8500 -50);
FORCEADD UNIVERSAL_GND..1
(8725 -575);
FORCEPROP 3 LASTPIN (8725 -525) SIG_NAME GND\g
J 0
(8735 -515);
DISPLAY 0.659574 (8735 -515);
PAINT MONO (8735 -515);
DISPLAY INVISIBLE (8735 -515);
FORCEPROP 2 LAST CDS_LIB logical_power
J 0
(8725 -575);
PAINT MONO (8725 -575);
DISPLAY INVISIBLE (8725 -575);
FORCEPROP 1 LAST HDL_POWER GND
J 1
(8750 -650);
DISPLAY 0.872340 (8750 -650);
PAINT GREEN (8750 -650);
DISPLAY INVISIBLE (8750 -650);
FORCEPROP 1 LAST PATH I176
J 0
(8800 -575);
DISPLAY 0.872340 (8800 -575);
PAINT AQUA (8800 -575);
DISPLAY INVISIBLE (8800 -575);
FORCEPROP 2 LAST ROOM IO_SLOT
J 1
(8500 -500);
DISPLAY 0.744681 (8500 -500);
DISPLAY INVISIBLE (8500 -500);
FORCEADD Q_CAP..1
(8725 -250);
FORCEPROP 1 LAST PART_NUMBER CH4104K1B00
J 0
(8775 -450);
DISPLAY 0.638298 (8775 -450);
DISPLAY INVISIBLE (8775 -450);
FORCEPROP 1 LAST VOLTAGE 25V
J 0
(8775 -250);
DISPLAY 0.638298 (8775 -250);
FORCEPROP 1 LAST TOLERANCE 10%
J 0
(8775 -300);
DISPLAY 0.638298 (8775 -300);
FORCEPROP 1 LAST MATERIAL X7R
J 0
(8775 -350);
DISPLAY 0.638298 (8775 -350);
FORCEPROP 1 LAST VALUE 0.1UF
J 0
(8775 -200);
DISPLAY 0.638298 (8775 -200);
FORCEPROP 1 LAST PACK_TYPE 0402
J 0
(8775 -400);
DISPLAY 0.638298 (8775 -400);
FORCEPROP 1 LAST $LOCATION C1838
J 0
(8775 -150);
DISPLAY 0.787234 (8775 -150);
FORCEPROP 1 LASTPIN (8725 -150) $PN 1
J 0
(8735 -170);
DISPLAY 0.787234 (8735 -170);
FORCEPROP 1 LASTPIN (8725 -350) $PN 2
J 0
(8735 -370);
DISPLAY 0.787234 (8735 -370);
FORCEPROP 2 LAST CDS_LIB pure_quanta
J 0
(8725 -250);
PAINT MONO (8725 -250);
DISPLAY INVISIBLE (8725 -250);
FORCEPROP 1 LAST PATH I177
J 0
(8775 -100);
DISPLAY 0.978723 (8775 -100);
PAINT WHITE (8775 -100);
DISPLAY INVISIBLE (8775 -100);
FORCEPROP 2 LAST CDS_LOCATION C1838
J 0
(8775 -50);
DISPLAY 1.021277 (8775 -50);
DISPLAY INVISIBLE (8775 -50);
FORCEPROP 2 LAST $SEC 1
J 0
(8775 -50);
DISPLAY 0.680851 (8775 -50);
PAINT MONO (8775 -50);
DISPLAY INVISIBLE (8775 -50);
FORCEPROP 2 LAST CDS_SEC 1
J 0
(8775 -50);
DISPLAY 1.021277 (8775 -50);
DISPLAY INVISIBLE (8775 -50);
FORCEADD UNIVERSAL_POWER..1
(7925 100);
FORCEPROP 3 LASTPIN (7925 50) SIG_NAME P3V3_OCP_V3_2\g
J 0
(7935 60);
DISPLAY 0.659574 (7935 60);
PAINT MONO (7935 60);
DISPLAY INVISIBLE (7935 60);
FORCEPROP 1 LAST HDL_POWER P3V3_OCP_V3_2
J 1
(7925 150);
DISPLAY 0.872340 (7925 150);
PAINT GREEN (7925 150);
FORCEPROP 2 LAST CDS_LIB logical_power
J 0
(7925 100);
PAINT MONO (7925 100);
DISPLAY INVISIBLE (7925 100);
FORCEPROP 1 LAST PATH I178
J 0
(7975 125);
DISPLAY 0.872340 (7975 125);
PAINT AQUA (7975 125);
DISPLAY INVISIBLE (7975 125);
FORCEADD Q_CAP..1
(6675 -250);
FORCEPROP 1 LAST PART_NUMBER CH4104K1B00
J 0
(6725 -400);
DISPLAY 0.808511 (6725 -400);
DISPLAY INVISIBLE (6725 -400);
FORCEPROP 1 LAST VALUE 0.1UF
J 0
(6725 -200);
DISPLAY 0.638298 (6725 -200);
FORCEPROP 1 LAST MATERIAL X7R
J 0
(6725 -350);
DISPLAY 0.638298 (6725 -350);
FORCEPROP 1 LAST PACK_TYPE 0402
J 0
(6725 -400);
DISPLAY 0.638298 (6725 -400);
FORCEPROP 1 LAST VOLTAGE 25V
J 0
(6725 -250);
DISPLAY 0.638298 (6725 -250);
FORCEPROP 1 LAST TOLERANCE 10%
J 0
(6725 -300);
DISPLAY 0.638298 (6725 -300);
FORCEPROP 1 LAST $LOCATION C1832
J 0
(6725 -150);
DISPLAY 0.787234 (6725 -150);
FORCEPROP 1 LASTPIN (6675 -150) $PN 1
J 0
(6685 -170);
DISPLAY 0.787234 (6685 -170);
FORCEPROP 1 LASTPIN (6675 -350) $PN 2
J 0
(6685 -370);
DISPLAY 0.787234 (6685 -370);
FORCEPROP 2 LAST CDS_LIB pure_quanta
J 0
(6675 -250);
PAINT MONO (6675 -250);
DISPLAY INVISIBLE (6675 -250);
FORCEPROP 1 LAST PATH I179
J 0
(6725 -100);
DISPLAY 0.978723 (6725 -100);
PAINT WHITE (6725 -100);
DISPLAY INVISIBLE (6725 -100);
FORCEPROP 2 LAST CDS_LOCATION C1832
J 0
(6725 -50);
DISPLAY 1.021277 (6725 -50);
DISPLAY INVISIBLE (6725 -50);
FORCEPROP 2 LAST $SEC 1
J 0
(6725 -50);
DISPLAY 0.680851 (6725 -50);
PAINT MONO (6725 -50);
DISPLAY INVISIBLE (6725 -50);
FORCEPROP 2 LAST CDS_SEC 1
J 0
(6725 -50);
DISPLAY 1.021277 (6725 -50);
DISPLAY INVISIBLE (6725 -50);
FORCEADD Q_CAP..1
(7175 -250);
FORCEPROP 1 LAST PART_NUMBER CH4104K1B00
J 0
(7225 -400);
DISPLAY 0.808511 (7225 -400);
DISPLAY INVISIBLE (7225 -400);
FORCEPROP 1 LAST VALUE 0.1UF
J 0
(7225 -200);
DISPLAY 0.638298 (7225 -200);
FORCEPROP 1 LAST PACK_TYPE 0402
J 0
(7225 -400);
DISPLAY 0.638298 (7225 -400);
FORCEPROP 1 LAST TOLERANCE 10%
J 0
(7225 -300);
DISPLAY 0.638298 (7225 -300);
FORCEPROP 1 LAST MATERIAL X7R
J 0
(7225 -350);
DISPLAY 0.638298 (7225 -350);
FORCEPROP 1 LAST VOLTAGE 25V
J 0
(7225 -250);
DISPLAY 0.638298 (7225 -250);
FORCEPROP 1 LAST $LOCATION C1839
J 0
(7225 -150);
DISPLAY 0.978723 (7225 -150);
FORCEPROP 1 LASTPIN (7175 -150) $PN 1
J 0
(7185 -170);
DISPLAY 0.787234 (7185 -170);
PAINT MONO (7185 -170);
FORCEPROP 1 LASTPIN (7175 -350) $PN 2
J 0
(7185 -370);
DISPLAY 0.787234 (7185 -370);
PAINT MONO (7185 -370);
FORCEPROP 2 LAST CDS_LIB pure_quanta
J 0
(7175 -250);
DISPLAY INVISIBLE (7175 -250);
FORCEPROP 1 LAST PATH I180
J 0
(7225 -100);
DISPLAY 0.978723 (7225 -100);
PAINT WHITE (7225 -100);
DISPLAY INVISIBLE (7225 -100);
FORCEPROP 0 LAST CDS_LOCATION C1839
J 0
(7225 -100);
DISPLAY 1.021277 (7225 -100);
DISPLAY INVISIBLE (7225 -100);
FORCEPROP 0 LAST $SEC 1
J 0
(7225 -100);
DISPLAY 0.680851 (7225 -100);
PAINT MONO (7225 -100);
DISPLAY INVISIBLE (7225 -100);
FORCEPROP 0 LAST CDS_SEC 1
J 0
(7225 -100);
DISPLAY 1.021277 (7225 -100);
DISPLAY INVISIBLE (7225 -100);
FORCEADD OFFPAGE..3
(7700 4025);
FORCEPROP 2 LAST $XR0 238 
J 0
(7914 4025);
DISPLAY 0.638298 (7914 4025);
PAINT MONO (7914 4025);
FORCEPROP 2 LAST CDS_LIB standard
J 0
(7700 4025);
PAINT MONO (7700 4025);
DISPLAY INVISIBLE (7700 4025);
FORCEPROP 1 LAST OFFPAGE TRUE
J 0
(8025 3900);
DISPLAY 0.872340 (8025 3900);
DISPLAY INVISIBLE (8025 3900);
FORCEPROP 1 LAST COMMENT_BODY TRUE
J 0
(7650 3925);
DISPLAY 0.872340 (7650 3925);
PAINT GREEN (7650 3925);
DISPLAY INVISIBLE (7650 3925);
FORCEPROP 2 LAST PATH I183
J 0
(7925 4075);
DISPLAY 1.021277 (7925 4075);
DISPLAY INVISIBLE (7925 4075);
FORCEADD OFFPAGE..4
(7700 4075);
FORCEPROP 2 LAST $XR0 238 
J 0
(7886 4075);
DISPLAY 0.638298 (7886 4075);
PAINT MONO (7886 4075);
FORCEPROP 2 LAST CDS_LIB standard
J 0
(7700 4075);
PAINT MONO (7700 4075);
DISPLAY INVISIBLE (7700 4075);
FORCEPROP 1 LAST OFFPAGE TRUE
J 0
(8025 3950);
DISPLAY 0.872340 (8025 3950);
PAINT GREEN (8025 3950);
DISPLAY INVISIBLE (8025 3950);
FORCEPROP 1 LAST COMMENT_BODY TRUE
J 0
(7675 3975);
DISPLAY 0.872340 (7675 3975);
PAINT GREEN (7675 3975);
DISPLAY INVISIBLE (7675 3975);
FORCEPROP 2 LAST PATH I184
J 0
(7900 4125);
DISPLAY 1.021277 (7900 4125);
DISPLAY INVISIBLE (7900 4125);
FORCEADD OFFPAGE..4
(7700 3975);
FORCEPROP 2 LAST $XR0 161 
J 0
(7916 3975);
DISPLAY 0.638298 (7916 3975);
PAINT MONO (7916 3975);
FORCEPROP 2 LAST CDS_LIB standard
J 0
(7700 3975);
DISPLAY INVISIBLE (7700 3975);
FORCEPROP 1 LAST OFFPAGE TRUE
J 0
(8025 3850);
DISPLAY 0.872340 (8025 3850);
PAINT GREEN (8025 3850);
DISPLAY INVISIBLE (8025 3850);
FORCEPROP 1 LAST COMMENT_BODY TRUE
J 0
(7675 3875);
DISPLAY 0.872340 (7675 3875);
PAINT GREEN (7675 3875);
DISPLAY INVISIBLE (7675 3875);
FORCEPROP 2 LAST PATH I186
J 0
(7875 4050);
DISPLAY 1.021277 (7875 4050);
DISPLAY INVISIBLE (7875 4050);
FORCEADD TAP..1
R 2
(3275 2475);
FORCEPROP 3 LASTPIN (3325 2475) SIG_NAME P5E_CPU1_PE1_TX_C_DN<6>
J 0
(3335 2485);
DISPLAY 0.659574 (3335 2485);
PAINT MONO (3335 2485);
DISPLAY INVISIBLE (3335 2485);
FORCEPROP 1 LASTPIN (3325 2475) BN 6
J 2
(3337 2483);
DISPLAY 0.680851 (3337 2483);
PAINT GREEN (3337 2483);
FORCEPROP 2 LAST CDS_LIB standard
J 0
(3275 2475);
PAINT MONO (3275 2475);
DISPLAY INVISIBLE (3275 2475);
FORCEPROP 1 LAST BODY_TYPE PLUMBING
J 2
(3275 2525);
DISPLAY 0.872340 (3275 2525);
PAINT GREEN (3275 2525);
DISPLAY INVISIBLE (3275 2525);
FORCEPROP 1 LAST HDL_TAP TRUE
J 2
(2950 2350);
DISPLAY 0.872340 (2950 2350);
PAINT GREEN (2950 2350);
DISPLAY INVISIBLE (2950 2350);
FORCEPROP 1 LAST PATH I188
J 2
(3277 2475);
DISPLAY 0.872340 (3277 2475);
PAINT GREEN (3277 2475);
DISPLAY INVISIBLE (3277 2475);
FORCEADD TAP..1
R 2
(3125 2525);
FORCEPROP 3 LASTPIN (3175 2525) SIG_NAME P5E_CPU1_PE1_TX_C_DP<6>
J 0
(3185 2535);
DISPLAY 0.659574 (3185 2535);
PAINT MONO (3185 2535);
DISPLAY INVISIBLE (3185 2535);
FORCEPROP 1 LASTPIN (3175 2525) BN 6
J 2
(3187 2533);
DISPLAY 0.680851 (3187 2533);
PAINT GREEN (3187 2533);
FORCEPROP 2 LAST CDS_LIB standard
J 0
(3125 2525);
PAINT MONO (3125 2525);
DISPLAY INVISIBLE (3125 2525);
FORCEPROP 1 LAST BODY_TYPE PLUMBING
J 2
(3125 2575);
DISPLAY 0.872340 (3125 2575);
PAINT GREEN (3125 2575);
DISPLAY INVISIBLE (3125 2575);
FORCEPROP 1 LAST HDL_TAP TRUE
J 2
(2800 2400);
DISPLAY 0.872340 (2800 2400);
PAINT GREEN (2800 2400);
DISPLAY INVISIBLE (2800 2400);
FORCEPROP 1 LAST PATH I189
J 2
(3127 2525);
DISPLAY 0.872340 (3127 2525);
PAINT GREEN (3127 2525);
DISPLAY INVISIBLE (3127 2525);
FORCEADD UNIVERSAL_GND..1
(775 -400);
FORCEPROP 3 LASTPIN (775 -350) SIG_NAME GND\g
J 0
(785 -340);
DISPLAY 0.659574 (785 -340);
PAINT MONO (785 -340);
DISPLAY INVISIBLE (785 -340);
FORCEPROP 2 LAST CDS_LIB logical_power
J 0
(775 -400);
PAINT MONO (775 -400);
DISPLAY INVISIBLE (775 -400);
FORCEPROP 1 LAST HDL_POWER GND
J 1
(800 -475);
DISPLAY 0.872340 (800 -475);
PAINT GREEN (800 -475);
DISPLAY INVISIBLE (800 -475);
FORCEPROP 1 LAST PATH I19
J 0
(850 -400);
DISPLAY 0.872340 (850 -400);
PAINT AQUA (850 -400);
DISPLAY INVISIBLE (850 -400);
FORCEPROP 2 LAST ROOM IO_SLOT
J 1
(550 -325);
DISPLAY 0.744681 (550 -325);
DISPLAY INVISIBLE (550 -325);
FORCEADD TAP..1
R 2
(3125 2025);
FORCEPROP 3 LASTPIN (3175 2025) SIG_NAME P5E_CPU1_PE1_TX_C_DP<8>
J 0
(3185 2035);
DISPLAY 0.659574 (3185 2035);
PAINT MONO (3185 2035);
DISPLAY INVISIBLE (3185 2035);
FORCEPROP 1 LASTPIN (3175 2025) BN 8
J 2
(3187 2033);
DISPLAY 0.680851 (3187 2033);
PAINT GREEN (3187 2033);
FORCEPROP 2 LAST CDS_LIB standard
J 0
(3125 2025);
PAINT MONO (3125 2025);
DISPLAY INVISIBLE (3125 2025);
FORCEPROP 1 LAST BODY_TYPE PLUMBING
J 2
(3125 2075);
DISPLAY 0.872340 (3125 2075);
PAINT GREEN (3125 2075);
DISPLAY INVISIBLE (3125 2075);
FORCEPROP 1 LAST HDL_TAP TRUE
J 2
(2800 1900);
DISPLAY 0.872340 (2800 1900);
PAINT GREEN (2800 1900);
DISPLAY INVISIBLE (2800 1900);
FORCEPROP 1 LAST PATH I191
J 2
(3127 2025);
DISPLAY 0.872340 (3127 2025);
PAINT GREEN (3127 2025);
DISPLAY INVISIBLE (3127 2025);
FORCEADD TAP..1
R 2
(3275 3525);
FORCEPROP 3 LASTPIN (3325 3525) SIG_NAME P5E_CPU1_PE1_TX_C_DN<0>
J 0
(3335 3535);
DISPLAY 0.659574 (3335 3535);
PAINT MONO (3335 3535);
DISPLAY INVISIBLE (3335 3535);
FORCEPROP 1 LASTPIN (3325 3525) BN 0
J 2
(3337 3533);
DISPLAY 0.680851 (3337 3533);
PAINT GREEN (3337 3533);
FORCEPROP 2 LAST CDS_LIB standard
J 0
(3275 3525);
DISPLAY INVISIBLE (3275 3525);
FORCEPROP 1 LAST BODY_TYPE PLUMBING
J 2
(3275 3575);
DISPLAY 0.872340 (3275 3575);
PAINT GREEN (3275 3575);
DISPLAY INVISIBLE (3275 3575);
FORCEPROP 1 LAST HDL_TAP TRUE
J 2
(2950 3400);
DISPLAY 0.872340 (2950 3400);
PAINT GREEN (2950 3400);
DISPLAY INVISIBLE (2950 3400);
FORCEPROP 1 LAST PATH I194
J 2
(3277 3525);
DISPLAY 0.872340 (3277 3525);
PAINT GREEN (3277 3525);
DISPLAY INVISIBLE (3277 3525);
FORCEADD TAP..1
R 2
(3125 3575);
FORCEPROP 3 LASTPIN (3175 3575) SIG_NAME P5E_CPU1_PE1_TX_C_DP<0>
J 0
(3185 3585);
DISPLAY 0.659574 (3185 3585);
PAINT MONO (3185 3585);
DISPLAY INVISIBLE (3185 3585);
FORCEPROP 1 LASTPIN (3175 3575) BN 0
J 2
(3187 3583);
DISPLAY 0.680851 (3187 3583);
PAINT GREEN (3187 3583);
FORCEPROP 2 LAST CDS_LIB standard
J 0
(3125 3575);
DISPLAY INVISIBLE (3125 3575);
FORCEPROP 1 LAST BODY_TYPE PLUMBING
J 2
(3125 3625);
DISPLAY 0.872340 (3125 3625);
PAINT GREEN (3125 3625);
DISPLAY INVISIBLE (3125 3625);
FORCEPROP 1 LAST HDL_TAP TRUE
J 2
(2800 3450);
DISPLAY 0.872340 (2800 3450);
PAINT GREEN (2800 3450);
DISPLAY INVISIBLE (2800 3450);
FORCEPROP 1 LAST PATH I196
J 2
(3127 3575);
DISPLAY 0.872340 (3127 3575);
PAINT GREEN (3127 3575);
DISPLAY INVISIBLE (3127 3575);
FORCEADD TAP..1
R 2
(3275 3225);
FORCEPROP 3 LASTPIN (3325 3225) SIG_NAME P5E_CPU1_PE1_TX_C_DN<2>
J 0
(3335 3235);
DISPLAY 0.659574 (3335 3235);
PAINT MONO (3335 3235);
DISPLAY INVISIBLE (3335 3235);
FORCEPROP 1 LASTPIN (3325 3225) BN 2
J 2
(3337 3233);
DISPLAY 0.680851 (3337 3233);
PAINT GREEN (3337 3233);
FORCEPROP 2 LAST CDS_LIB standard
J 0
(3275 3225);
PAINT MONO (3275 3225);
DISPLAY INVISIBLE (3275 3225);
FORCEPROP 1 LAST BODY_TYPE PLUMBING
J 2
(3275 3275);
DISPLAY 0.872340 (3275 3275);
PAINT GREEN (3275 3275);
DISPLAY INVISIBLE (3275 3275);
FORCEPROP 1 LAST HDL_TAP TRUE
J 2
(2950 3100);
DISPLAY 0.872340 (2950 3100);
PAINT GREEN (2950 3100);
DISPLAY INVISIBLE (2950 3100);
FORCEPROP 1 LAST PATH I198
J 2
(3277 3225);
DISPLAY 0.872340 (3277 3225);
PAINT GREEN (3277 3225);
DISPLAY INVISIBLE (3277 3225);
FORCEADD TAP..1
R 2
(3125 3275);
FORCEPROP 3 LASTPIN (3175 3275) SIG_NAME P5E_CPU1_PE1_TX_C_DP<2>
J 0
(3185 3285);
DISPLAY 0.659574 (3185 3285);
PAINT MONO (3185 3285);
DISPLAY INVISIBLE (3185 3285);
FORCEPROP 1 LASTPIN (3175 3275) BN 2
J 2
(3187 3283);
DISPLAY 0.680851 (3187 3283);
PAINT GREEN (3187 3283);
FORCEPROP 2 LAST CDS_LIB standard
J 0
(3125 3275);
PAINT MONO (3125 3275);
DISPLAY INVISIBLE (3125 3275);
FORCEPROP 1 LAST BODY_TYPE PLUMBING
J 2
(3125 3325);
DISPLAY 0.872340 (3125 3325);
PAINT GREEN (3125 3325);
DISPLAY INVISIBLE (3125 3325);
FORCEPROP 1 LAST HDL_TAP TRUE
J 2
(2800 3150);
DISPLAY 0.872340 (2800 3150);
PAINT GREEN (2800 3150);
DISPLAY INVISIBLE (2800 3150);
FORCEPROP 1 LAST PATH I199
J 2
(3127 3275);
DISPLAY 0.872340 (3127 3275);
PAINT GREEN (3127 3275);
DISPLAY INVISIBLE (3127 3275);
FORCEADD Q_RES..2
(775 -175);
FORCEPROP 1 LAST PART_NUMBER CS24702FB06
J 0
(815 -300);
DISPLAY 0.787234 (815 -300);
DISPLAY INVISIBLE (815 -300);
FORCEPROP 1 LAST PACK_TYPE 0402LF
J 0
(815 -350);
DISPLAY 0.787234 (815 -350);
FORCEPROP 1 LAST VALUE 4.7K
J 0
(820 -100);
DISPLAY 0.787234 (820 -100);
FORCEPROP 1 LAST WATTAGE 1/16W
J 0
(815 -200);
DISPLAY 0.787234 (815 -200);
FORCEPROP 1 LAST MATERIAL CHIP
J 0
(815 -250);
DISPLAY 0.787234 (815 -250);
FORCEPROP 1 LAST TOLERANCE 1%
J 0
(820 -150);
DISPLAY 0.787234 (820 -150);
FORCEPROP 1 LAST $LOCATION R3167
J 0
(820 -50);
DISPLAY 0.978723 (820 -50);
FORCEPROP 1 LASTPIN (775 -75) $PN 1
J 0
(780 -113);
DISPLAY 0.787234 (780 -113);
FORCEPROP 1 LASTPIN (775 -275) $PN 2
J 0
(780 -265);
DISPLAY 0.787234 (780 -265);
FORCEPROP 2 LAST CDS_LIB pure_quanta
J 0
(775 -175);
PAINT MONO (775 -175);
DISPLAY INVISIBLE (775 -175);
FORCEPROP 1 LAST PATH I20
J 0
(825 0);
DISPLAY 0.978723 (825 0);
PAINT WHITE (825 0);
DISPLAY INVISIBLE (825 0);
FORCEPROP 2 LAST CDS_LOCATION R3167
J 0
(825 50);
DISPLAY 1.021277 (825 50);
DISPLAY INVISIBLE (825 50);
FORCEPROP 2 LAST $SEC 1
J 0
(825 50);
DISPLAY 0.680851 (825 50);
PAINT MONO (825 50);
DISPLAY INVISIBLE (825 50);
FORCEPROP 2 LAST CDS_SEC 1
J 0
(825 50);
DISPLAY 1.021277 (825 50);
DISPLAY INVISIBLE (825 50);
FORCEADD TAP..1
R 2
(3125 2825);
FORCEPROP 3 LASTPIN (3175 2825) SIG_NAME P5E_CPU1_PE1_TX_C_DP<4>
J 0
(3185 2835);
DISPLAY 0.659574 (3185 2835);
PAINT MONO (3185 2835);
DISPLAY INVISIBLE (3185 2835);
FORCEPROP 1 LASTPIN (3175 2825) BN 4
J 2
(3187 2833);
DISPLAY 0.680851 (3187 2833);
PAINT GREEN (3187 2833);
FORCEPROP 2 LAST CDS_LIB standard
J 0
(3125 2825);
PAINT MONO (3125 2825);
DISPLAY INVISIBLE (3125 2825);
FORCEPROP 1 LAST BODY_TYPE PLUMBING
J 2
(3125 2875);
DISPLAY 0.872340 (3125 2875);
PAINT GREEN (3125 2875);
DISPLAY INVISIBLE (3125 2875);
FORCEPROP 1 LAST HDL_TAP TRUE
J 2
(2800 2700);
DISPLAY 0.872340 (2800 2700);
PAINT GREEN (2800 2700);
DISPLAY INVISIBLE (2800 2700);
FORCEPROP 1 LAST PATH I201
J 2
(3127 2825);
DISPLAY 0.872340 (3127 2825);
PAINT GREEN (3127 2825);
DISPLAY INVISIBLE (3127 2825);
FORCEADD TAP..1
R 2
(3275 2775);
FORCEPROP 3 LASTPIN (3325 2775) SIG_NAME P5E_CPU1_PE1_TX_C_DN<4>
J 0
(3335 2785);
DISPLAY 0.659574 (3335 2785);
PAINT MONO (3335 2785);
DISPLAY INVISIBLE (3335 2785);
FORCEPROP 1 LASTPIN (3325 2775) BN 4
J 2
(3337 2783);
DISPLAY 0.680851 (3337 2783);
PAINT GREEN (3337 2783);
FORCEPROP 2 LAST CDS_LIB standard
J 0
(3275 2775);
PAINT MONO (3275 2775);
DISPLAY INVISIBLE (3275 2775);
FORCEPROP 1 LAST BODY_TYPE PLUMBING
J 2
(3275 2825);
DISPLAY 0.872340 (3275 2825);
PAINT GREEN (3275 2825);
DISPLAY INVISIBLE (3275 2825);
FORCEPROP 1 LAST HDL_TAP TRUE
J 2
(2950 2650);
DISPLAY 0.872340 (2950 2650);
PAINT GREEN (2950 2650);
DISPLAY INVISIBLE (2950 2650);
FORCEPROP 1 LAST PATH I203
J 2
(3277 2775);
DISPLAY 0.872340 (3277 2775);
PAINT GREEN (3277 2775);
DISPLAY INVISIBLE (3277 2775);
FORCEADD TAP..1
R 2
(3275 1975);
FORCEPROP 3 LASTPIN (3325 1975) SIG_NAME P5E_CPU1_PE1_TX_C_DN<8>
J 0
(3335 1985);
DISPLAY 0.659574 (3335 1985);
PAINT MONO (3335 1985);
DISPLAY INVISIBLE (3335 1985);
FORCEPROP 1 LASTPIN (3325 1975) BN 8
J 2
(3337 1983);
DISPLAY 0.680851 (3337 1983);
PAINT GREEN (3337 1983);
FORCEPROP 2 LAST CDS_LIB standard
J 0
(3275 1975);
PAINT MONO (3275 1975);
DISPLAY INVISIBLE (3275 1975);
FORCEPROP 1 LAST BODY_TYPE PLUMBING
J 2
(3275 2025);
DISPLAY 0.872340 (3275 2025);
PAINT GREEN (3275 2025);
DISPLAY INVISIBLE (3275 2025);
FORCEPROP 1 LAST HDL_TAP TRUE
J 2
(2950 1850);
DISPLAY 0.872340 (2950 1850);
PAINT GREEN (2950 1850);
DISPLAY INVISIBLE (2950 1850);
FORCEPROP 1 LAST PATH I208
J 2
(3277 1975);
DISPLAY 0.872340 (3277 1975);
PAINT GREEN (3277 1975);
DISPLAY INVISIBLE (3277 1975);
FORCEADD OFFPAGE..2
(1375 50);
FORCEPROP 2 LAST $XR0 159 
J 0
(1564 50);
DISPLAY 0.638298 (1564 50);
PAINT MONO (1564 50);
FORCEPROP 2 LAST CDS_LIB standard
J 0
(1375 50);
PAINT MONO (1375 50);
DISPLAY INVISIBLE (1375 50);
FORCEPROP 1 LAST OFFPAGE TRUE
J 0
(1700 -75);
DISPLAY 0.872340 (1700 -75);
PAINT GREEN (1700 -75);
DISPLAY INVISIBLE (1700 -75);
FORCEPROP 1 LAST COMMENT_BODY TRUE
J 0
(1330 -45);
DISPLAY 0.872340 (1330 -45);
PAINT GREEN (1330 -45);
DISPLAY INVISIBLE (1330 -45);
FORCEPROP 2 LAST PATH I21
J 0
(1575 100);
DISPLAY 1.021277 (1575 100);
DISPLAY INVISIBLE (1575 100);
FORCEADD TAP..1
R 2
(3275 1675);
FORCEPROP 3 LASTPIN (3325 1675) SIG_NAME P5E_CPU1_PE1_TX_C_DN<10>
J 0
(3335 1685);
DISPLAY 0.659574 (3335 1685);
PAINT MONO (3335 1685);
DISPLAY INVISIBLE (3335 1685);
FORCEPROP 1 LASTPIN (3325 1675) BN 10
J 2
(3337 1683);
DISPLAY 0.680851 (3337 1683);
PAINT GREEN (3337 1683);
FORCEPROP 2 LAST CDS_LIB standard
J 0
(3275 1675);
PAINT MONO (3275 1675);
DISPLAY INVISIBLE (3275 1675);
FORCEPROP 1 LAST BODY_TYPE PLUMBING
J 2
(3275 1725);
DISPLAY 0.872340 (3275 1725);
PAINT GREEN (3275 1725);
DISPLAY INVISIBLE (3275 1725);
FORCEPROP 1 LAST HDL_TAP TRUE
J 2
(2950 1550);
DISPLAY 0.872340 (2950 1550);
PAINT GREEN (2950 1550);
DISPLAY INVISIBLE (2950 1550);
FORCEPROP 1 LAST PATH I210
J 2
(3277 1675);
DISPLAY 0.872340 (3277 1675);
PAINT GREEN (3277 1675);
DISPLAY INVISIBLE (3277 1675);
FORCEADD TAP..1
R 2
(3125 1725);
FORCEPROP 3 LASTPIN (3175 1725) SIG_NAME P5E_CPU1_PE1_TX_C_DP<10>
J 0
(3185 1735);
DISPLAY 0.659574 (3185 1735);
PAINT MONO (3185 1735);
DISPLAY INVISIBLE (3185 1735);
FORCEPROP 1 LASTPIN (3175 1725) BN 10
J 2
(3187 1733);
DISPLAY 0.680851 (3187 1733);
PAINT GREEN (3187 1733);
FORCEPROP 2 LAST CDS_LIB standard
J 0
(3125 1725);
PAINT MONO (3125 1725);
DISPLAY INVISIBLE (3125 1725);
FORCEPROP 1 LAST BODY_TYPE PLUMBING
J 2
(3125 1775);
DISPLAY 0.872340 (3125 1775);
PAINT GREEN (3125 1775);
DISPLAY INVISIBLE (3125 1775);
FORCEPROP 1 LAST HDL_TAP TRUE
J 2
(2800 1600);
DISPLAY 0.872340 (2800 1600);
PAINT GREEN (2800 1600);
DISPLAY INVISIBLE (2800 1600);
FORCEPROP 1 LAST PATH I212
J 2
(3127 1725);
DISPLAY 0.872340 (3127 1725);
PAINT GREEN (3127 1725);
DISPLAY INVISIBLE (3127 1725);
FORCEADD TAP..1
R 2
(3275 1375);
FORCEPROP 3 LASTPIN (3325 1375) SIG_NAME P5E_CPU1_PE1_TX_C_DN<12>
J 0
(3335 1385);
DISPLAY 0.659574 (3335 1385);
PAINT MONO (3335 1385);
DISPLAY INVISIBLE (3335 1385);
FORCEPROP 1 LASTPIN (3325 1375) BN 12
J 2
(3337 1383);
DISPLAY 0.680851 (3337 1383);
PAINT GREEN (3337 1383);
FORCEPROP 2 LAST CDS_LIB standard
J 0
(3275 1375);
PAINT MONO (3275 1375);
DISPLAY INVISIBLE (3275 1375);
FORCEPROP 1 LAST BODY_TYPE PLUMBING
J 2
(3275 1425);
DISPLAY 0.872340 (3275 1425);
PAINT GREEN (3275 1425);
DISPLAY INVISIBLE (3275 1425);
FORCEPROP 1 LAST HDL_TAP TRUE
J 2
(2950 1250);
DISPLAY 0.872340 (2950 1250);
PAINT GREEN (2950 1250);
DISPLAY INVISIBLE (2950 1250);
FORCEPROP 1 LAST PATH I213
J 2
(3277 1375);
DISPLAY 0.872340 (3277 1375);
PAINT GREEN (3277 1375);
DISPLAY INVISIBLE (3277 1375);
FORCEADD TAP..1
R 2
(3125 1425);
FORCEPROP 3 LASTPIN (3175 1425) SIG_NAME P5E_CPU1_PE1_TX_C_DP<12>
J 0
(3185 1435);
DISPLAY 0.659574 (3185 1435);
PAINT MONO (3185 1435);
DISPLAY INVISIBLE (3185 1435);
FORCEPROP 1 LASTPIN (3175 1425) BN 12
J 2
(3187 1433);
DISPLAY 0.680851 (3187 1433);
PAINT GREEN (3187 1433);
FORCEPROP 2 LAST CDS_LIB standard
J 0
(3125 1425);
PAINT MONO (3125 1425);
DISPLAY INVISIBLE (3125 1425);
FORCEPROP 1 LAST BODY_TYPE PLUMBING
J 2
(3125 1475);
DISPLAY 0.872340 (3125 1475);
PAINT GREEN (3125 1475);
DISPLAY INVISIBLE (3125 1475);
FORCEPROP 1 LAST HDL_TAP TRUE
J 2
(2800 1300);
DISPLAY 0.872340 (2800 1300);
PAINT GREEN (2800 1300);
DISPLAY INVISIBLE (2800 1300);
FORCEPROP 1 LAST PATH I214
J 2
(3127 1425);
DISPLAY 0.872340 (3127 1425);
PAINT GREEN (3127 1425);
DISPLAY INVISIBLE (3127 1425);
FORCEADD TAP..1
R 2
(3275 1075);
FORCEPROP 3 LASTPIN (3325 1075) SIG_NAME P5E_CPU1_PE1_TX_C_DN<14>
J 0
(3335 1085);
DISPLAY 0.659574 (3335 1085);
PAINT MONO (3335 1085);
DISPLAY INVISIBLE (3335 1085);
FORCEPROP 1 LASTPIN (3325 1075) BN 14
J 2
(3337 1083);
DISPLAY 0.680851 (3337 1083);
PAINT GREEN (3337 1083);
FORCEPROP 2 LAST CDS_LIB standard
J 0
(3275 1075);
PAINT MONO (3275 1075);
DISPLAY INVISIBLE (3275 1075);
FORCEPROP 1 LAST BODY_TYPE PLUMBING
J 2
(3275 1125);
DISPLAY 0.872340 (3275 1125);
PAINT GREEN (3275 1125);
DISPLAY INVISIBLE (3275 1125);
FORCEPROP 1 LAST HDL_TAP TRUE
J 2
(2950 950);
DISPLAY 0.872340 (2950 950);
PAINT GREEN (2950 950);
DISPLAY INVISIBLE (2950 950);
FORCEPROP 1 LAST PATH I216
J 2
(3277 1075);
DISPLAY 0.872340 (3277 1075);
PAINT GREEN (3277 1075);
DISPLAY INVISIBLE (3277 1075);
FORCEADD TAP..1
R 2
(3125 1125);
FORCEPROP 3 LASTPIN (3175 1125) SIG_NAME P5E_CPU1_PE1_TX_C_DP<14>
J 0
(3185 1135);
DISPLAY 0.659574 (3185 1135);
PAINT MONO (3185 1135);
DISPLAY INVISIBLE (3185 1135);
FORCEPROP 1 LASTPIN (3175 1125) BN 14
J 2
(3187 1133);
DISPLAY 0.680851 (3187 1133);
PAINT GREEN (3187 1133);
FORCEPROP 2 LAST CDS_LIB standard
J 0
(3125 1125);
PAINT MONO (3125 1125);
DISPLAY INVISIBLE (3125 1125);
FORCEPROP 1 LAST BODY_TYPE PLUMBING
J 2
(3125 1175);
DISPLAY 0.872340 (3125 1175);
PAINT GREEN (3125 1175);
DISPLAY INVISIBLE (3125 1175);
FORCEPROP 1 LAST HDL_TAP TRUE
J 2
(2800 1000);
DISPLAY 0.872340 (2800 1000);
PAINT GREEN (2800 1000);
DISPLAY INVISIBLE (2800 1000);
FORCEPROP 1 LAST PATH I218
J 2
(3127 1125);
DISPLAY 0.872340 (3127 1125);
PAINT GREEN (3127 1125);
DISPLAY INVISIBLE (3127 1125);
FORCEADD OFFPAGE..2
(1375 100);
FORCEPROP 2 LAST $XR0 159 
J 0
(1564 100);
DISPLAY 0.638298 (1564 100);
PAINT MONO (1564 100);
FORCEPROP 2 LAST CDS_LIB standard
J 0
(1375 100);
PAINT MONO (1375 100);
DISPLAY INVISIBLE (1375 100);
FORCEPROP 1 LAST OFFPAGE TRUE
J 0
(1700 -25);
DISPLAY 0.872340 (1700 -25);
PAINT GREEN (1700 -25);
DISPLAY INVISIBLE (1700 -25);
FORCEPROP 1 LAST COMMENT_BODY TRUE
J 0
(1330 5);
DISPLAY 0.872340 (1330 5);
PAINT GREEN (1330 5);
DISPLAY INVISIBLE (1330 5);
FORCEPROP 2 LAST PATH I22
J 0
(1575 150);
DISPLAY 1.021277 (1575 150);
DISPLAY INVISIBLE (1575 150);
FORCEADD OFFPAGE..1
(2075 3600);
FORCEPROP 2 LAST $XR0 175 
J 0
(1823 3600);
DISPLAY 0.638298 (1823 3600);
PAINT MONO (1823 3600);
FORCEPROP 2 LAST CDS_LIB standard
J 0
(2075 3600);
DISPLAY INVISIBLE (2075 3600);
FORCEPROP 1 LAST OFFPAGE TRUE
J 0
(2400 3475);
DISPLAY 0.872340 (2400 3475);
PAINT GREEN (2400 3475);
DISPLAY INVISIBLE (2400 3475);
FORCEPROP 1 LAST COMMENT_BODY TRUE
J 0
(2200 3500);
DISPLAY 0.872340 (2200 3500);
PAINT GREEN (2200 3500);
DISPLAY INVISIBLE (2200 3500);
FORCEPROP 2 LAST PATH I220
J 0
(1825 3650);
DISPLAY 1.021277 (1825 3650);
DISPLAY INVISIBLE (1825 3650);
FORCEADD OFFPAGE..1
(2075 3550);
FORCEPROP 2 LAST $XR0 175 
J 0
(1823 3550);
DISPLAY 0.638298 (1823 3550);
PAINT MONO (1823 3550);
FORCEPROP 2 LAST CDS_LIB standard
J 0
(2075 3550);
DISPLAY INVISIBLE (2075 3550);
FORCEPROP 1 LAST OFFPAGE TRUE
J 0
(2400 3425);
DISPLAY 0.872340 (2400 3425);
PAINT GREEN (2400 3425);
DISPLAY INVISIBLE (2400 3425);
FORCEPROP 1 LAST COMMENT_BODY TRUE
J 0
(2200 3450);
DISPLAY 0.872340 (2200 3450);
PAINT GREEN (2200 3450);
DISPLAY INVISIBLE (2200 3450);
FORCEPROP 2 LAST PATH I221
J 0
(1825 3600);
DISPLAY 1.021277 (1825 3600);
DISPLAY INVISIBLE (1825 3600);
FORCEADD OFFPAGE..2
(6825 3600);
FORCEPROP 2 LAST $XR0 60 
J 0
(7014 3600);
DISPLAY 0.638298 (7014 3600);
PAINT MONO (7014 3600);
FORCEPROP 2 LAST CDS_LIB standard
J 0
(6825 3600);
DISPLAY INVISIBLE (6825 3600);
FORCEPROP 1 LAST OFFPAGE TRUE
J 0
(7150 3475);
DISPLAY 0.872340 (7150 3475);
PAINT GREEN (7150 3475);
DISPLAY INVISIBLE (7150 3475);
FORCEPROP 1 LAST COMMENT_BODY TRUE
J 0
(6780 3505);
DISPLAY 0.872340 (6780 3505);
PAINT GREEN (6780 3505);
DISPLAY INVISIBLE (6780 3505);
FORCEPROP 2 LAST PATH I222
J 0
(7025 3650);
DISPLAY 1.021277 (7025 3650);
DISPLAY INVISIBLE (7025 3650);
FORCEADD OFFPAGE..2
(6825 3550);
FORCEPROP 2 LAST $XR0 60 
J 0
(7014 3550);
DISPLAY 0.638298 (7014 3550);
PAINT MONO (7014 3550);
FORCEPROP 2 LAST CDS_LIB standard
J 0
(6825 3550);
DISPLAY INVISIBLE (6825 3550);
FORCEPROP 1 LAST OFFPAGE TRUE
J 0
(7150 3425);
DISPLAY 0.872340 (7150 3425);
PAINT GREEN (7150 3425);
DISPLAY INVISIBLE (7150 3425);
FORCEPROP 1 LAST COMMENT_BODY TRUE
J 0
(6780 3455);
DISPLAY 0.872340 (6780 3455);
PAINT GREEN (6780 3455);
DISPLAY INVISIBLE (6780 3455);
FORCEPROP 2 LAST PATH I223
J 0
(7025 3600);
DISPLAY 1.021277 (7025 3600);
DISPLAY INVISIBLE (7025 3600);
FORCEADD TAP..1
(5775 3575);
FORCEPROP 3 LASTPIN (5725 3575) SIG_NAME P5E_CPU1_PE1_RX_DN<0>
J 0
(5735 3585);
DISPLAY 0.659574 (5735 3585);
PAINT MONO (5735 3585);
DISPLAY INVISIBLE (5735 3585);
FORCEPROP 1 LASTPIN (5725 3575) BN 0
J 0
(5713 3583);
DISPLAY 0.680851 (5713 3583);
PAINT GREEN (5713 3583);
FORCEPROP 2 LAST CDS_LIB standard
J 0
(5775 3575);
PAINT MONO (5775 3575);
DISPLAY INVISIBLE (5775 3575);
FORCEPROP 1 LAST BODY_TYPE PLUMBING
J 0
(5775 3625);
DISPLAY 0.872340 (5775 3625);
PAINT GREEN (5775 3625);
DISPLAY INVISIBLE (5775 3625);
FORCEPROP 1 LAST HDL_TAP TRUE
J 0
(6100 3450);
DISPLAY 0.872340 (6100 3450);
DISPLAY INVISIBLE (6100 3450);
FORCEPROP 1 LAST PATH I224
J 0
(5773 3575);
DISPLAY 0.872340 (5773 3575);
PAINT GREEN (5773 3575);
DISPLAY INVISIBLE (5773 3575);
FORCEADD TAP..1
(5775 3425);
FORCEPROP 3 LASTPIN (5725 3425) SIG_NAME P5E_CPU1_PE1_RX_DN<1>
J 0
(5735 3435);
DISPLAY 0.659574 (5735 3435);
PAINT MONO (5735 3435);
DISPLAY INVISIBLE (5735 3435);
FORCEPROP 1 LASTPIN (5725 3425) BN 1
J 0
(5713 3433);
DISPLAY 0.680851 (5713 3433);
PAINT GREEN (5713 3433);
FORCEPROP 2 LAST CDS_LIB standard
J 0
(5775 3425);
PAINT MONO (5775 3425);
DISPLAY INVISIBLE (5775 3425);
FORCEPROP 1 LAST BODY_TYPE PLUMBING
J 0
(5775 3475);
DISPLAY 0.872340 (5775 3475);
PAINT GREEN (5775 3475);
DISPLAY INVISIBLE (5775 3475);
FORCEPROP 1 LAST HDL_TAP TRUE
J 0
(6100 3300);
DISPLAY 0.872340 (6100 3300);
PAINT GREEN (6100 3300);
DISPLAY INVISIBLE (6100 3300);
FORCEPROP 1 LAST PATH I225
J 0
(5773 3425);
DISPLAY 0.872340 (5773 3425);
PAINT GREEN (5773 3425);
DISPLAY INVISIBLE (5773 3425);
FORCEADD TAP..1
(5775 3275);
FORCEPROP 3 LASTPIN (5725 3275) SIG_NAME P5E_CPU1_PE1_RX_DN<2>
J 0
(5735 3285);
DISPLAY 0.659574 (5735 3285);
PAINT MONO (5735 3285);
DISPLAY INVISIBLE (5735 3285);
FORCEPROP 1 LASTPIN (5725 3275) BN 2
J 0
(5713 3283);
DISPLAY 0.680851 (5713 3283);
PAINT GREEN (5713 3283);
FORCEPROP 2 LAST CDS_LIB standard
J 0
(5775 3275);
PAINT MONO (5775 3275);
DISPLAY INVISIBLE (5775 3275);
FORCEPROP 1 LAST BODY_TYPE PLUMBING
J 0
(5775 3325);
DISPLAY 0.872340 (5775 3325);
PAINT GREEN (5775 3325);
DISPLAY INVISIBLE (5775 3325);
FORCEPROP 1 LAST HDL_TAP TRUE
J 0
(6100 3150);
DISPLAY 0.872340 (6100 3150);
PAINT GREEN (6100 3150);
DISPLAY INVISIBLE (6100 3150);
FORCEPROP 1 LAST PATH I226
J 0
(5773 3275);
DISPLAY 0.872340 (5773 3275);
PAINT GREEN (5773 3275);
DISPLAY INVISIBLE (5773 3275);
FORCEADD TAP..1
(5775 3125);
FORCEPROP 3 LASTPIN (5725 3125) SIG_NAME P5E_CPU1_PE1_RX_DN<3>
J 0
(5735 3135);
DISPLAY 0.659574 (5735 3135);
PAINT MONO (5735 3135);
DISPLAY INVISIBLE (5735 3135);
FORCEPROP 1 LASTPIN (5725 3125) BN 3
J 0
(5713 3133);
DISPLAY 0.680851 (5713 3133);
PAINT GREEN (5713 3133);
FORCEPROP 2 LAST CDS_LIB standard
J 0
(5775 3125);
PAINT MONO (5775 3125);
DISPLAY INVISIBLE (5775 3125);
FORCEPROP 1 LAST BODY_TYPE PLUMBING
J 0
(5775 3175);
DISPLAY 0.872340 (5775 3175);
PAINT GREEN (5775 3175);
DISPLAY INVISIBLE (5775 3175);
FORCEPROP 1 LAST HDL_TAP TRUE
J 0
(6100 3000);
DISPLAY 0.872340 (6100 3000);
PAINT GREEN (6100 3000);
DISPLAY INVISIBLE (6100 3000);
FORCEPROP 1 LAST PATH I227
J 0
(5773 3125);
DISPLAY 0.872340 (5773 3125);
PAINT GREEN (5773 3125);
DISPLAY INVISIBLE (5773 3125);
FORCEADD TAP..1
(5775 2825);
FORCEPROP 3 LASTPIN (5725 2825) SIG_NAME P5E_CPU1_PE1_RX_DN<4>
J 0
(5735 2835);
DISPLAY 0.659574 (5735 2835);
PAINT MONO (5735 2835);
DISPLAY INVISIBLE (5735 2835);
FORCEPROP 1 LASTPIN (5725 2825) BN 4
J 0
(5713 2833);
DISPLAY 0.680851 (5713 2833);
PAINT GREEN (5713 2833);
FORCEPROP 2 LAST CDS_LIB standard
J 0
(5775 2825);
PAINT MONO (5775 2825);
DISPLAY INVISIBLE (5775 2825);
FORCEPROP 1 LAST BODY_TYPE PLUMBING
J 0
(5775 2875);
DISPLAY 0.872340 (5775 2875);
PAINT GREEN (5775 2875);
DISPLAY INVISIBLE (5775 2875);
FORCEPROP 1 LAST HDL_TAP TRUE
J 0
(6100 2700);
DISPLAY 0.872340 (6100 2700);
PAINT GREEN (6100 2700);
DISPLAY INVISIBLE (6100 2700);
FORCEPROP 1 LAST PATH I228
J 0
(5773 2825);
DISPLAY 0.872340 (5773 2825);
PAINT GREEN (5773 2825);
DISPLAY INVISIBLE (5773 2825);
FORCEADD TAP..1
(5775 2675);
FORCEPROP 3 LASTPIN (5725 2675) SIG_NAME P5E_CPU1_PE1_RX_DN<5>
J 0
(5735 2685);
DISPLAY 0.659574 (5735 2685);
PAINT MONO (5735 2685);
DISPLAY INVISIBLE (5735 2685);
FORCEPROP 1 LASTPIN (5725 2675) BN 5
J 0
(5713 2683);
DISPLAY 0.680851 (5713 2683);
PAINT GREEN (5713 2683);
FORCEPROP 2 LAST CDS_LIB standard
J 0
(5775 2675);
PAINT MONO (5775 2675);
DISPLAY INVISIBLE (5775 2675);
FORCEPROP 1 LAST BODY_TYPE PLUMBING
J 0
(5775 2725);
DISPLAY 0.872340 (5775 2725);
PAINT GREEN (5775 2725);
DISPLAY INVISIBLE (5775 2725);
FORCEPROP 1 LAST HDL_TAP TRUE
J 0
(6100 2550);
DISPLAY 0.872340 (6100 2550);
PAINT GREEN (6100 2550);
DISPLAY INVISIBLE (6100 2550);
FORCEPROP 1 LAST PATH I229
J 0
(5773 2675);
DISPLAY 0.872340 (5773 2675);
PAINT GREEN (5773 2675);
DISPLAY INVISIBLE (5773 2675);
FORCEADD Q_RES..2
(775 350);
FORCEPROP 1 LAST PART_NUMBER CS24702FB06
J 0
(815 225);
DISPLAY 0.787234 (815 225);
DISPLAY INVISIBLE (815 225);
FORCEPROP 1 LAST TOLERANCE 1%
J 0
(820 375);
DISPLAY 0.787234 (820 375);
FORCEPROP 1 LAST PACK_TYPE 0402LF
J 0
(815 175);
DISPLAY 0.787234 (815 175);
FORCEPROP 1 LAST MATERIAL EMPTY
J 0
(815 275);
DISPLAY 0.787234 (815 275);
FORCEPROP 1 LAST WATTAGE 1/16W
J 0
(815 325);
DISPLAY 0.787234 (815 325);
FORCEPROP 1 LAST VALUE 4.7K
J 0
(820 425);
DISPLAY 0.787234 (820 425);
FORCEPROP 1 LAST $LOCATION R3166
J 0
(820 475);
DISPLAY 0.978723 (820 475);
FORCEPROP 1 LASTPIN (775 450) $PN 1
J 0
(780 412);
DISPLAY 0.787234 (780 412);
FORCEPROP 1 LASTPIN (775 250) $PN 2
J 0
(780 260);
DISPLAY 0.787234 (780 260);
FORCEPROP 2 LAST CDS_LIB pure_quanta
J 0
(775 350);
PAINT MONO (775 350);
DISPLAY INVISIBLE (775 350);
FORCEPROP 1 LAST PATH I23
J 0
(825 525);
DISPLAY 0.978723 (825 525);
PAINT WHITE (825 525);
DISPLAY INVISIBLE (825 525);
FORCEPROP 2 LAST CDS_LOCATION R3166
J 0
(825 575);
DISPLAY 1.021277 (825 575);
DISPLAY INVISIBLE (825 575);
FORCEPROP 2 LAST $SEC 1
J 0
(825 575);
DISPLAY 0.680851 (825 575);
PAINT MONO (825 575);
DISPLAY INVISIBLE (825 575);
FORCEPROP 2 LAST CDS_SEC 1
J 0
(825 575);
DISPLAY 1.021277 (825 575);
DISPLAY INVISIBLE (825 575);
FORCEADD TAP..1
(5625 3525);
FORCEPROP 3 LASTPIN (5575 3525) SIG_NAME P5E_CPU1_PE1_RX_DP<0>
J 0
(5585 3535);
DISPLAY 0.659574 (5585 3535);
PAINT MONO (5585 3535);
DISPLAY INVISIBLE (5585 3535);
FORCEPROP 1 LASTPIN (5575 3525) BN 0
J 0
(5563 3533);
DISPLAY 0.680851 (5563 3533);
PAINT GREEN (5563 3533);
FORCEPROP 2 LAST CDS_LIB standard
J 0
(5625 3525);
PAINT MONO (5625 3525);
DISPLAY INVISIBLE (5625 3525);
FORCEPROP 1 LAST BODY_TYPE PLUMBING
J 0
(5625 3575);
DISPLAY 0.872340 (5625 3575);
PAINT GREEN (5625 3575);
DISPLAY INVISIBLE (5625 3575);
FORCEPROP 1 LAST HDL_TAP TRUE
J 0
(5950 3400);
DISPLAY 0.872340 (5950 3400);
PAINT GREEN (5950 3400);
DISPLAY INVISIBLE (5950 3400);
FORCEPROP 1 LAST PATH I230
J 0
(5623 3525);
DISPLAY 0.872340 (5623 3525);
PAINT GREEN (5623 3525);
DISPLAY INVISIBLE (5623 3525);
FORCEADD TAP..1
(5625 3375);
FORCEPROP 3 LASTPIN (5575 3375) SIG_NAME P5E_CPU1_PE1_RX_DP<1>
J 0
(5585 3385);
DISPLAY 0.659574 (5585 3385);
PAINT MONO (5585 3385);
DISPLAY INVISIBLE (5585 3385);
FORCEPROP 1 LASTPIN (5575 3375) BN 1
J 0
(5563 3383);
DISPLAY 0.680851 (5563 3383);
PAINT GREEN (5563 3383);
FORCEPROP 2 LAST CDS_LIB standard
J 0
(5625 3375);
PAINT MONO (5625 3375);
DISPLAY INVISIBLE (5625 3375);
FORCEPROP 1 LAST BODY_TYPE PLUMBING
J 0
(5625 3425);
DISPLAY 0.872340 (5625 3425);
PAINT GREEN (5625 3425);
DISPLAY INVISIBLE (5625 3425);
FORCEPROP 1 LAST HDL_TAP TRUE
J 0
(5950 3250);
DISPLAY 0.872340 (5950 3250);
PAINT GREEN (5950 3250);
DISPLAY INVISIBLE (5950 3250);
FORCEPROP 1 LAST PATH I231
J 0
(5623 3375);
DISPLAY 0.872340 (5623 3375);
PAINT GREEN (5623 3375);
DISPLAY INVISIBLE (5623 3375);
FORCEADD TAP..1
(5625 3225);
FORCEPROP 3 LASTPIN (5575 3225) SIG_NAME P5E_CPU1_PE1_RX_DP<2>
J 0
(5585 3235);
DISPLAY 0.659574 (5585 3235);
PAINT MONO (5585 3235);
DISPLAY INVISIBLE (5585 3235);
FORCEPROP 1 LASTPIN (5575 3225) BN 2
J 0
(5563 3233);
DISPLAY 0.680851 (5563 3233);
PAINT GREEN (5563 3233);
FORCEPROP 2 LAST CDS_LIB standard
J 0
(5625 3225);
PAINT MONO (5625 3225);
DISPLAY INVISIBLE (5625 3225);
FORCEPROP 1 LAST BODY_TYPE PLUMBING
J 0
(5625 3275);
DISPLAY 0.872340 (5625 3275);
PAINT GREEN (5625 3275);
DISPLAY INVISIBLE (5625 3275);
FORCEPROP 1 LAST HDL_TAP TRUE
J 0
(5950 3100);
DISPLAY 0.872340 (5950 3100);
PAINT GREEN (5950 3100);
DISPLAY INVISIBLE (5950 3100);
FORCEPROP 1 LAST PATH I232
J 0
(5623 3225);
DISPLAY 0.872340 (5623 3225);
PAINT GREEN (5623 3225);
DISPLAY INVISIBLE (5623 3225);
FORCEADD TAP..1
(5625 3075);
FORCEPROP 3 LASTPIN (5575 3075) SIG_NAME P5E_CPU1_PE1_RX_DP<3>
J 0
(5585 3085);
DISPLAY 0.659574 (5585 3085);
PAINT MONO (5585 3085);
DISPLAY INVISIBLE (5585 3085);
FORCEPROP 1 LASTPIN (5575 3075) BN 3
J 0
(5563 3083);
DISPLAY 0.680851 (5563 3083);
PAINT GREEN (5563 3083);
FORCEPROP 2 LAST CDS_LIB standard
J 0
(5625 3075);
PAINT MONO (5625 3075);
DISPLAY INVISIBLE (5625 3075);
FORCEPROP 1 LAST BODY_TYPE PLUMBING
J 0
(5625 3125);
DISPLAY 0.872340 (5625 3125);
PAINT GREEN (5625 3125);
DISPLAY INVISIBLE (5625 3125);
FORCEPROP 1 LAST HDL_TAP TRUE
J 0
(5950 2950);
DISPLAY 0.872340 (5950 2950);
PAINT GREEN (5950 2950);
DISPLAY INVISIBLE (5950 2950);
FORCEPROP 1 LAST PATH I233
J 0
(5623 3075);
DISPLAY 0.872340 (5623 3075);
PAINT GREEN (5623 3075);
DISPLAY INVISIBLE (5623 3075);
FORCEADD TAP..1
(5625 2775);
FORCEPROP 3 LASTPIN (5575 2775) SIG_NAME P5E_CPU1_PE1_RX_DP<4>
J 0
(5585 2785);
DISPLAY 0.659574 (5585 2785);
PAINT MONO (5585 2785);
DISPLAY INVISIBLE (5585 2785);
FORCEPROP 1 LASTPIN (5575 2775) BN 4
J 0
(5563 2783);
DISPLAY 0.680851 (5563 2783);
PAINT GREEN (5563 2783);
FORCEPROP 2 LAST CDS_LIB standard
J 0
(5625 2775);
PAINT MONO (5625 2775);
DISPLAY INVISIBLE (5625 2775);
FORCEPROP 1 LAST BODY_TYPE PLUMBING
J 0
(5625 2825);
DISPLAY 0.872340 (5625 2825);
PAINT GREEN (5625 2825);
DISPLAY INVISIBLE (5625 2825);
FORCEPROP 1 LAST HDL_TAP TRUE
J 0
(5950 2650);
DISPLAY 0.872340 (5950 2650);
PAINT GREEN (5950 2650);
DISPLAY INVISIBLE (5950 2650);
FORCEPROP 1 LAST PATH I234
J 0
(5623 2775);
DISPLAY 0.872340 (5623 2775);
PAINT GREEN (5623 2775);
DISPLAY INVISIBLE (5623 2775);
FORCEADD TAP..1
(5775 2525);
FORCEPROP 3 LASTPIN (5725 2525) SIG_NAME P5E_CPU1_PE1_RX_DN<6>
J 0
(5735 2535);
DISPLAY 0.659574 (5735 2535);
PAINT MONO (5735 2535);
DISPLAY INVISIBLE (5735 2535);
FORCEPROP 1 LASTPIN (5725 2525) BN 6
J 0
(5713 2533);
DISPLAY 0.680851 (5713 2533);
PAINT GREEN (5713 2533);
FORCEPROP 2 LAST CDS_LIB standard
J 0
(5775 2525);
PAINT MONO (5775 2525);
DISPLAY INVISIBLE (5775 2525);
FORCEPROP 1 LAST BODY_TYPE PLUMBING
J 0
(5775 2575);
DISPLAY 0.872340 (5775 2575);
PAINT GREEN (5775 2575);
DISPLAY INVISIBLE (5775 2575);
FORCEPROP 1 LAST HDL_TAP TRUE
J 0
(6100 2400);
DISPLAY 0.872340 (6100 2400);
PAINT GREEN (6100 2400);
DISPLAY INVISIBLE (6100 2400);
FORCEPROP 1 LAST PATH I235
J 0
(5773 2525);
DISPLAY 0.872340 (5773 2525);
PAINT GREEN (5773 2525);
DISPLAY INVISIBLE (5773 2525);
FORCEADD TAP..1
(5775 2375);
FORCEPROP 3 LASTPIN (5725 2375) SIG_NAME P5E_CPU1_PE1_RX_DN<7>
J 0
(5735 2385);
DISPLAY 0.659574 (5735 2385);
PAINT MONO (5735 2385);
DISPLAY INVISIBLE (5735 2385);
FORCEPROP 1 LASTPIN (5725 2375) BN 7
J 0
(5713 2383);
DISPLAY 0.680851 (5713 2383);
PAINT GREEN (5713 2383);
FORCEPROP 2 LAST CDS_LIB standard
J 0
(5775 2375);
PAINT MONO (5775 2375);
DISPLAY INVISIBLE (5775 2375);
FORCEPROP 1 LAST BODY_TYPE PLUMBING
J 0
(5775 2425);
DISPLAY 0.872340 (5775 2425);
PAINT GREEN (5775 2425);
DISPLAY INVISIBLE (5775 2425);
FORCEPROP 1 LAST HDL_TAP TRUE
J 0
(6100 2250);
DISPLAY 0.872340 (6100 2250);
PAINT GREEN (6100 2250);
DISPLAY INVISIBLE (6100 2250);
FORCEPROP 1 LAST PATH I236
J 0
(5773 2375);
DISPLAY 0.872340 (5773 2375);
PAINT GREEN (5773 2375);
DISPLAY INVISIBLE (5773 2375);
FORCEADD TAP..1
(5775 2025);
FORCEPROP 3 LASTPIN (5725 2025) SIG_NAME P5E_CPU1_PE1_RX_DN<8>
J 0
(5735 2035);
DISPLAY 0.659574 (5735 2035);
PAINT MONO (5735 2035);
DISPLAY INVISIBLE (5735 2035);
FORCEPROP 1 LASTPIN (5725 2025) BN 8
J 0
(5713 2033);
DISPLAY 0.680851 (5713 2033);
PAINT GREEN (5713 2033);
FORCEPROP 2 LAST CDS_LIB standard
J 0
(5775 2025);
PAINT MONO (5775 2025);
DISPLAY INVISIBLE (5775 2025);
FORCEPROP 1 LAST BODY_TYPE PLUMBING
J 0
(5775 2075);
DISPLAY 0.872340 (5775 2075);
PAINT GREEN (5775 2075);
DISPLAY INVISIBLE (5775 2075);
FORCEPROP 1 LAST HDL_TAP TRUE
J 0
(6100 1900);
DISPLAY 0.872340 (6100 1900);
PAINT GREEN (6100 1900);
DISPLAY INVISIBLE (6100 1900);
FORCEPROP 1 LAST PATH I237
J 0
(5773 2025);
DISPLAY 0.872340 (5773 2025);
PAINT GREEN (5773 2025);
DISPLAY INVISIBLE (5773 2025);
FORCEADD TAP..1
(5775 1875);
FORCEPROP 3 LASTPIN (5725 1875) SIG_NAME P5E_CPU1_PE1_RX_DN<9>
J 0
(5735 1885);
DISPLAY 0.659574 (5735 1885);
PAINT MONO (5735 1885);
DISPLAY INVISIBLE (5735 1885);
FORCEPROP 1 LASTPIN (5725 1875) BN 9
J 0
(5713 1883);
DISPLAY 0.680851 (5713 1883);
PAINT GREEN (5713 1883);
FORCEPROP 2 LAST CDS_LIB standard
J 0
(5775 1875);
PAINT MONO (5775 1875);
DISPLAY INVISIBLE (5775 1875);
FORCEPROP 1 LAST BODY_TYPE PLUMBING
J 0
(5775 1925);
DISPLAY 0.872340 (5775 1925);
PAINT GREEN (5775 1925);
DISPLAY INVISIBLE (5775 1925);
FORCEPROP 1 LAST HDL_TAP TRUE
J 0
(6100 1750);
DISPLAY 0.872340 (6100 1750);
PAINT GREEN (6100 1750);
DISPLAY INVISIBLE (6100 1750);
FORCEPROP 1 LAST PATH I238
J 0
(5773 1875);
DISPLAY 0.872340 (5773 1875);
PAINT GREEN (5773 1875);
DISPLAY INVISIBLE (5773 1875);
FORCEADD TAP..1
(5775 1725);
FORCEPROP 3 LASTPIN (5725 1725) SIG_NAME P5E_CPU1_PE1_RX_DN<10>
J 0
(5735 1735);
DISPLAY 0.659574 (5735 1735);
PAINT MONO (5735 1735);
DISPLAY INVISIBLE (5735 1735);
FORCEPROP 1 LASTPIN (5725 1725) BN 10
J 0
(5713 1733);
DISPLAY 0.680851 (5713 1733);
PAINT GREEN (5713 1733);
FORCEPROP 2 LAST CDS_LIB standard
J 0
(5775 1725);
PAINT MONO (5775 1725);
DISPLAY INVISIBLE (5775 1725);
FORCEPROP 1 LAST BODY_TYPE PLUMBING
J 0
(5775 1775);
DISPLAY 0.872340 (5775 1775);
PAINT GREEN (5775 1775);
DISPLAY INVISIBLE (5775 1775);
FORCEPROP 1 LAST HDL_TAP TRUE
J 0
(6100 1600);
DISPLAY 0.872340 (6100 1600);
PAINT GREEN (6100 1600);
DISPLAY INVISIBLE (6100 1600);
FORCEPROP 1 LAST PATH I239
J 0
(5773 1725);
DISPLAY 0.872340 (5773 1725);
PAINT GREEN (5773 1725);
DISPLAY INVISIBLE (5773 1725);
FORCEADD UNIVERSAL_POWER..1
(300 650);
FORCEPROP 3 LASTPIN (300 600) SIG_NAME P3V3_OCP_V3_2\g
J 0
(310 610);
DISPLAY 0.659574 (310 610);
PAINT MONO (310 610);
DISPLAY INVISIBLE (310 610);
FORCEPROP 1 LAST HDL_POWER P3V3_OCP_V3_2
J 1
(300 700);
DISPLAY 0.872340 (300 700);
PAINT GREEN (300 700);
FORCEPROP 2 LAST CDS_LIB logical_power
J 0
(300 650);
PAINT MONO (300 650);
DISPLAY INVISIBLE (300 650);
FORCEPROP 1 LAST PATH I24
J 0
(350 675);
DISPLAY 0.872340 (350 675);
PAINT AQUA (350 675);
DISPLAY INVISIBLE (350 675);
FORCEADD TAP..1
(5625 2625);
FORCEPROP 3 LASTPIN (5575 2625) SIG_NAME P5E_CPU1_PE1_RX_DP<5>
J 0
(5585 2635);
DISPLAY 0.659574 (5585 2635);
PAINT MONO (5585 2635);
DISPLAY INVISIBLE (5585 2635);
FORCEPROP 1 LASTPIN (5575 2625) BN 5
J 0
(5563 2633);
DISPLAY 0.680851 (5563 2633);
PAINT GREEN (5563 2633);
FORCEPROP 2 LAST CDS_LIB standard
J 0
(5625 2625);
PAINT MONO (5625 2625);
DISPLAY INVISIBLE (5625 2625);
FORCEPROP 1 LAST BODY_TYPE PLUMBING
J 0
(5625 2675);
DISPLAY 0.872340 (5625 2675);
PAINT GREEN (5625 2675);
DISPLAY INVISIBLE (5625 2675);
FORCEPROP 1 LAST HDL_TAP TRUE
J 0
(5950 2500);
DISPLAY 0.872340 (5950 2500);
PAINT GREEN (5950 2500);
DISPLAY INVISIBLE (5950 2500);
FORCEPROP 1 LAST PATH I240
J 0
(5623 2625);
DISPLAY 0.872340 (5623 2625);
PAINT GREEN (5623 2625);
DISPLAY INVISIBLE (5623 2625);
FORCEADD TAP..1
(5625 2475);
FORCEPROP 3 LASTPIN (5575 2475) SIG_NAME P5E_CPU1_PE1_RX_DP<6>
J 0
(5585 2485);
DISPLAY 0.659574 (5585 2485);
PAINT MONO (5585 2485);
DISPLAY INVISIBLE (5585 2485);
FORCEPROP 1 LASTPIN (5575 2475) BN 6
J 0
(5563 2483);
DISPLAY 0.680851 (5563 2483);
PAINT GREEN (5563 2483);
FORCEPROP 2 LAST CDS_LIB standard
J 0
(5625 2475);
PAINT MONO (5625 2475);
DISPLAY INVISIBLE (5625 2475);
FORCEPROP 1 LAST BODY_TYPE PLUMBING
J 0
(5625 2525);
DISPLAY 0.872340 (5625 2525);
PAINT GREEN (5625 2525);
DISPLAY INVISIBLE (5625 2525);
FORCEPROP 1 LAST HDL_TAP TRUE
J 0
(5950 2350);
DISPLAY 0.872340 (5950 2350);
PAINT GREEN (5950 2350);
DISPLAY INVISIBLE (5950 2350);
FORCEPROP 1 LAST PATH I241
J 0
(5623 2475);
DISPLAY 0.872340 (5623 2475);
PAINT GREEN (5623 2475);
DISPLAY INVISIBLE (5623 2475);
FORCEADD TAP..1
(5625 2325);
FORCEPROP 3 LASTPIN (5575 2325) SIG_NAME P5E_CPU1_PE1_RX_DP<7>
J 0
(5585 2335);
DISPLAY 0.659574 (5585 2335);
PAINT MONO (5585 2335);
DISPLAY INVISIBLE (5585 2335);
FORCEPROP 1 LASTPIN (5575 2325) BN 7
J 0
(5563 2333);
DISPLAY 0.680851 (5563 2333);
PAINT GREEN (5563 2333);
FORCEPROP 2 LAST CDS_LIB standard
J 0
(5625 2325);
PAINT MONO (5625 2325);
DISPLAY INVISIBLE (5625 2325);
FORCEPROP 1 LAST BODY_TYPE PLUMBING
J 0
(5625 2375);
DISPLAY 0.872340 (5625 2375);
PAINT GREEN (5625 2375);
DISPLAY INVISIBLE (5625 2375);
FORCEPROP 1 LAST HDL_TAP TRUE
J 0
(5950 2200);
DISPLAY 0.872340 (5950 2200);
PAINT GREEN (5950 2200);
DISPLAY INVISIBLE (5950 2200);
FORCEPROP 1 LAST PATH I242
J 0
(5623 2325);
DISPLAY 0.872340 (5623 2325);
PAINT GREEN (5623 2325);
DISPLAY INVISIBLE (5623 2325);
FORCEADD TAP..1
(5625 1975);
FORCEPROP 3 LASTPIN (5575 1975) SIG_NAME P5E_CPU1_PE1_RX_DP<8>
J 0
(5585 1985);
DISPLAY 0.659574 (5585 1985);
PAINT MONO (5585 1985);
DISPLAY INVISIBLE (5585 1985);
FORCEPROP 1 LASTPIN (5575 1975) BN 8
J 0
(5563 1983);
DISPLAY 0.680851 (5563 1983);
PAINT GREEN (5563 1983);
FORCEPROP 2 LAST CDS_LIB standard
J 0
(5625 1975);
PAINT MONO (5625 1975);
DISPLAY INVISIBLE (5625 1975);
FORCEPROP 1 LAST BODY_TYPE PLUMBING
J 0
(5625 2025);
DISPLAY 0.872340 (5625 2025);
PAINT GREEN (5625 2025);
DISPLAY INVISIBLE (5625 2025);
FORCEPROP 1 LAST HDL_TAP TRUE
J 0
(5950 1850);
DISPLAY 0.872340 (5950 1850);
PAINT GREEN (5950 1850);
DISPLAY INVISIBLE (5950 1850);
FORCEPROP 1 LAST PATH I243
J 0
(5623 1975);
DISPLAY 0.872340 (5623 1975);
PAINT GREEN (5623 1975);
DISPLAY INVISIBLE (5623 1975);
FORCEADD TAP..1
(5625 1825);
FORCEPROP 3 LASTPIN (5575 1825) SIG_NAME P5E_CPU1_PE1_RX_DP<9>
J 0
(5585 1835);
DISPLAY 0.659574 (5585 1835);
PAINT MONO (5585 1835);
DISPLAY INVISIBLE (5585 1835);
FORCEPROP 1 LASTPIN (5575 1825) BN 9
J 0
(5563 1833);
DISPLAY 0.680851 (5563 1833);
PAINT GREEN (5563 1833);
FORCEPROP 2 LAST CDS_LIB standard
J 0
(5625 1825);
PAINT MONO (5625 1825);
DISPLAY INVISIBLE (5625 1825);
FORCEPROP 1 LAST BODY_TYPE PLUMBING
J 0
(5625 1875);
DISPLAY 0.872340 (5625 1875);
PAINT GREEN (5625 1875);
DISPLAY INVISIBLE (5625 1875);
FORCEPROP 1 LAST HDL_TAP TRUE
J 0
(5950 1700);
DISPLAY 0.872340 (5950 1700);
PAINT GREEN (5950 1700);
DISPLAY INVISIBLE (5950 1700);
FORCEPROP 1 LAST PATH I244
J 0
(5623 1825);
DISPLAY 0.872340 (5623 1825);
PAINT GREEN (5623 1825);
DISPLAY INVISIBLE (5623 1825);
FORCEADD TAP..1
(5625 1675);
FORCEPROP 3 LASTPIN (5575 1675) SIG_NAME P5E_CPU1_PE1_RX_DP<10>
J 0
(5585 1685);
DISPLAY 0.659574 (5585 1685);
PAINT MONO (5585 1685);
DISPLAY INVISIBLE (5585 1685);
FORCEPROP 1 LASTPIN (5575 1675) BN 10
J 0
(5563 1683);
DISPLAY 0.680851 (5563 1683);
PAINT GREEN (5563 1683);
FORCEPROP 2 LAST CDS_LIB standard
J 0
(5625 1675);
PAINT MONO (5625 1675);
DISPLAY INVISIBLE (5625 1675);
FORCEPROP 1 LAST BODY_TYPE PLUMBING
J 0
(5625 1725);
DISPLAY 0.872340 (5625 1725);
PAINT GREEN (5625 1725);
DISPLAY INVISIBLE (5625 1725);
FORCEPROP 1 LAST HDL_TAP TRUE
J 0
(5950 1550);
DISPLAY 0.872340 (5950 1550);
PAINT GREEN (5950 1550);
DISPLAY INVISIBLE (5950 1550);
FORCEPROP 1 LAST PATH I245
J 0
(5623 1675);
DISPLAY 0.872340 (5623 1675);
PAINT GREEN (5623 1675);
DISPLAY INVISIBLE (5623 1675);
FORCEADD TAP..1
(5775 1575);
FORCEPROP 3 LASTPIN (5725 1575) SIG_NAME P5E_CPU1_PE1_RX_DN<11>
J 0
(5735 1585);
DISPLAY 0.659574 (5735 1585);
PAINT MONO (5735 1585);
DISPLAY INVISIBLE (5735 1585);
FORCEPROP 1 LASTPIN (5725 1575) BN 11
J 0
(5713 1583);
DISPLAY 0.680851 (5713 1583);
PAINT GREEN (5713 1583);
FORCEPROP 2 LAST CDS_LIB standard
J 0
(5775 1575);
PAINT MONO (5775 1575);
DISPLAY INVISIBLE (5775 1575);
FORCEPROP 1 LAST BODY_TYPE PLUMBING
J 0
(5775 1625);
DISPLAY 0.872340 (5775 1625);
PAINT GREEN (5775 1625);
DISPLAY INVISIBLE (5775 1625);
FORCEPROP 1 LAST HDL_TAP TRUE
J 0
(6100 1450);
DISPLAY 0.872340 (6100 1450);
PAINT GREEN (6100 1450);
DISPLAY INVISIBLE (6100 1450);
FORCEPROP 1 LAST PATH I246
J 0
(5773 1575);
DISPLAY 0.872340 (5773 1575);
PAINT GREEN (5773 1575);
DISPLAY INVISIBLE (5773 1575);
FORCEADD TAP..1
(5775 1425);
FORCEPROP 3 LASTPIN (5725 1425) SIG_NAME P5E_CPU1_PE1_RX_DN<12>
J 0
(5735 1435);
DISPLAY 0.659574 (5735 1435);
PAINT MONO (5735 1435);
DISPLAY INVISIBLE (5735 1435);
FORCEPROP 1 LASTPIN (5725 1425) BN 12
J 0
(5713 1433);
DISPLAY 0.680851 (5713 1433);
PAINT GREEN (5713 1433);
FORCEPROP 2 LAST CDS_LIB standard
J 0
(5775 1425);
PAINT MONO (5775 1425);
DISPLAY INVISIBLE (5775 1425);
FORCEPROP 1 LAST BODY_TYPE PLUMBING
J 0
(5775 1475);
DISPLAY 0.872340 (5775 1475);
PAINT GREEN (5775 1475);
DISPLAY INVISIBLE (5775 1475);
FORCEPROP 1 LAST HDL_TAP TRUE
J 0
(6100 1300);
DISPLAY 0.872340 (6100 1300);
PAINT GREEN (6100 1300);
DISPLAY INVISIBLE (6100 1300);
FORCEPROP 1 LAST PATH I247
J 0
(5773 1425);
DISPLAY 0.872340 (5773 1425);
PAINT GREEN (5773 1425);
DISPLAY INVISIBLE (5773 1425);
FORCEADD TAP..1
(5775 1275);
FORCEPROP 3 LASTPIN (5725 1275) SIG_NAME P5E_CPU1_PE1_RX_DN<13>
J 0
(5735 1285);
DISPLAY 0.659574 (5735 1285);
PAINT MONO (5735 1285);
DISPLAY INVISIBLE (5735 1285);
FORCEPROP 1 LASTPIN (5725 1275) BN 13
J 0
(5713 1283);
DISPLAY 0.680851 (5713 1283);
PAINT GREEN (5713 1283);
FORCEPROP 2 LAST CDS_LIB standard
J 0
(5775 1275);
PAINT MONO (5775 1275);
DISPLAY INVISIBLE (5775 1275);
FORCEPROP 1 LAST BODY_TYPE PLUMBING
J 0
(5775 1325);
DISPLAY 0.872340 (5775 1325);
PAINT GREEN (5775 1325);
DISPLAY INVISIBLE (5775 1325);
FORCEPROP 1 LAST HDL_TAP TRUE
J 0
(6100 1150);
DISPLAY 0.872340 (6100 1150);
PAINT GREEN (6100 1150);
DISPLAY INVISIBLE (6100 1150);
FORCEPROP 1 LAST PATH I248
J 0
(5773 1275);
DISPLAY 0.872340 (5773 1275);
PAINT GREEN (5773 1275);
DISPLAY INVISIBLE (5773 1275);
FORCEADD TAP..1
(5775 1125);
FORCEPROP 3 LASTPIN (5725 1125) SIG_NAME P5E_CPU1_PE1_RX_DN<14>
J 0
(5735 1135);
DISPLAY 0.659574 (5735 1135);
PAINT MONO (5735 1135);
DISPLAY INVISIBLE (5735 1135);
FORCEPROP 1 LASTPIN (5725 1125) BN 14
J 0
(5713 1133);
DISPLAY 0.680851 (5713 1133);
PAINT GREEN (5713 1133);
FORCEPROP 2 LAST CDS_LIB standard
J 0
(5775 1125);
PAINT MONO (5775 1125);
DISPLAY INVISIBLE (5775 1125);
FORCEPROP 1 LAST BODY_TYPE PLUMBING
J 0
(5775 1175);
DISPLAY 0.872340 (5775 1175);
PAINT GREEN (5775 1175);
DISPLAY INVISIBLE (5775 1175);
FORCEPROP 1 LAST HDL_TAP TRUE
J 0
(6100 1000);
DISPLAY 0.872340 (6100 1000);
PAINT GREEN (6100 1000);
DISPLAY INVISIBLE (6100 1000);
FORCEPROP 1 LAST PATH I249
J 0
(5773 1125);
DISPLAY 0.872340 (5773 1125);
PAINT GREEN (5773 1125);
DISPLAY INVISIBLE (5773 1125);
FORCEADD Q_RES..2
(300 -175);
FORCEPROP 1 LAST PART_NUMBER CS24702FB06
J 0
(340 -300);
DISPLAY 0.787234 (340 -300);
DISPLAY INVISIBLE (340 -300);
FORCEPROP 1 LAST WATTAGE 1/16W
J 0
(340 -200);
DISPLAY 0.787234 (340 -200);
FORCEPROP 1 LAST MATERIAL EMPTY
J 0
(340 -250);
DISPLAY 0.787234 (340 -250);
FORCEPROP 1 LAST PACK_TYPE 0402LF
J 0
(340 -350);
DISPLAY 0.787234 (340 -350);
FORCEPROP 1 LAST TOLERANCE 1%
J 0
(345 -150);
DISPLAY 0.787234 (345 -150);
FORCEPROP 1 LAST VALUE 4.7K
J 0
(345 -100);
DISPLAY 0.787234 (345 -100);
FORCEPROP 1 LAST $LOCATION R3163
J 0
(345 -50);
DISPLAY 0.978723 (345 -50);
FORCEPROP 1 LASTPIN (300 -75) $PN 1
J 0
(305 -113);
DISPLAY 0.787234 (305 -113);
FORCEPROP 1 LASTPIN (300 -275) $PN 2
J 0
(305 -265);
DISPLAY 0.787234 (305 -265);
FORCEPROP 2 LAST CDS_LIB pure_quanta
J 0
(300 -175);
PAINT MONO (300 -175);
DISPLAY INVISIBLE (300 -175);
FORCEPROP 1 LAST PATH I25
J 0
(350 0);
DISPLAY 0.978723 (350 0);
PAINT WHITE (350 0);
DISPLAY INVISIBLE (350 0);
FORCEPROP 2 LAST CDS_LOCATION R3163
J 0
(350 50);
DISPLAY 1.021277 (350 50);
DISPLAY INVISIBLE (350 50);
FORCEPROP 2 LAST $SEC 1
J 0
(350 50);
DISPLAY 0.680851 (350 50);
PAINT MONO (350 50);
DISPLAY INVISIBLE (350 50);
FORCEPROP 2 LAST CDS_SEC 1
J 0
(350 50);
DISPLAY 1.021277 (350 50);
DISPLAY INVISIBLE (350 50);
FORCEADD TAP..1
(5775 975);
FORCEPROP 3 LASTPIN (5725 975) SIG_NAME P5E_CPU1_PE1_RX_DN<15>
J 0
(5735 985);
DISPLAY 0.659574 (5735 985);
PAINT MONO (5735 985);
DISPLAY INVISIBLE (5735 985);
FORCEPROP 1 LASTPIN (5725 975) BN 15
J 0
(5713 983);
DISPLAY 0.680851 (5713 983);
PAINT GREEN (5713 983);
FORCEPROP 2 LAST CDS_LIB standard
J 0
(5775 975);
PAINT MONO (5775 975);
DISPLAY INVISIBLE (5775 975);
FORCEPROP 1 LAST BODY_TYPE PLUMBING
J 0
(5775 1025);
DISPLAY 0.872340 (5775 1025);
PAINT GREEN (5775 1025);
DISPLAY INVISIBLE (5775 1025);
FORCEPROP 1 LAST HDL_TAP TRUE
J 0
(6100 850);
DISPLAY 0.872340 (6100 850);
PAINT GREEN (6100 850);
DISPLAY INVISIBLE (6100 850);
FORCEPROP 1 LAST PATH I250
J 0
(5773 975);
DISPLAY 0.872340 (5773 975);
PAINT GREEN (5773 975);
DISPLAY INVISIBLE (5773 975);
FORCEADD TAP..1
(5625 1525);
FORCEPROP 3 LASTPIN (5575 1525) SIG_NAME P5E_CPU1_PE1_RX_DP<11>
J 0
(5585 1535);
DISPLAY 0.659574 (5585 1535);
PAINT MONO (5585 1535);
DISPLAY INVISIBLE (5585 1535);
FORCEPROP 1 LASTPIN (5575 1525) BN 11
J 0
(5563 1533);
DISPLAY 0.680851 (5563 1533);
PAINT GREEN (5563 1533);
FORCEPROP 2 LAST CDS_LIB standard
J 0
(5625 1525);
PAINT MONO (5625 1525);
DISPLAY INVISIBLE (5625 1525);
FORCEPROP 1 LAST BODY_TYPE PLUMBING
J 0
(5625 1575);
DISPLAY 0.872340 (5625 1575);
PAINT GREEN (5625 1575);
DISPLAY INVISIBLE (5625 1575);
FORCEPROP 1 LAST HDL_TAP TRUE
J 0
(5950 1400);
DISPLAY 0.872340 (5950 1400);
PAINT GREEN (5950 1400);
DISPLAY INVISIBLE (5950 1400);
FORCEPROP 1 LAST PATH I251
J 0
(5623 1525);
DISPLAY 0.872340 (5623 1525);
PAINT GREEN (5623 1525);
DISPLAY INVISIBLE (5623 1525);
FORCEADD TAP..1
(5625 1375);
FORCEPROP 3 LASTPIN (5575 1375) SIG_NAME P5E_CPU1_PE1_RX_DP<12>
J 0
(5585 1385);
DISPLAY 0.659574 (5585 1385);
PAINT MONO (5585 1385);
DISPLAY INVISIBLE (5585 1385);
FORCEPROP 1 LASTPIN (5575 1375) BN 12
J 0
(5563 1383);
DISPLAY 0.680851 (5563 1383);
PAINT GREEN (5563 1383);
FORCEPROP 2 LAST CDS_LIB standard
J 0
(5625 1375);
PAINT MONO (5625 1375);
DISPLAY INVISIBLE (5625 1375);
FORCEPROP 1 LAST BODY_TYPE PLUMBING
J 0
(5625 1425);
DISPLAY 0.872340 (5625 1425);
PAINT GREEN (5625 1425);
DISPLAY INVISIBLE (5625 1425);
FORCEPROP 1 LAST HDL_TAP TRUE
J 0
(5950 1250);
DISPLAY 0.872340 (5950 1250);
PAINT GREEN (5950 1250);
DISPLAY INVISIBLE (5950 1250);
FORCEPROP 1 LAST PATH I252
J 0
(5623 1375);
DISPLAY 0.872340 (5623 1375);
PAINT GREEN (5623 1375);
DISPLAY INVISIBLE (5623 1375);
FORCEADD TAP..1
(5625 1225);
FORCEPROP 3 LASTPIN (5575 1225) SIG_NAME P5E_CPU1_PE1_RX_DP<13>
J 0
(5585 1235);
DISPLAY 0.659574 (5585 1235);
PAINT MONO (5585 1235);
DISPLAY INVISIBLE (5585 1235);
FORCEPROP 1 LASTPIN (5575 1225) BN 13
J 0
(5563 1233);
DISPLAY 0.680851 (5563 1233);
PAINT GREEN (5563 1233);
FORCEPROP 2 LAST CDS_LIB standard
J 0
(5625 1225);
PAINT MONO (5625 1225);
DISPLAY INVISIBLE (5625 1225);
FORCEPROP 1 LAST BODY_TYPE PLUMBING
J 0
(5625 1275);
DISPLAY 0.872340 (5625 1275);
PAINT GREEN (5625 1275);
DISPLAY INVISIBLE (5625 1275);
FORCEPROP 1 LAST HDL_TAP TRUE
J 0
(5950 1100);
DISPLAY 0.872340 (5950 1100);
PAINT GREEN (5950 1100);
DISPLAY INVISIBLE (5950 1100);
FORCEPROP 1 LAST PATH I253
J 0
(5623 1225);
DISPLAY 0.872340 (5623 1225);
PAINT GREEN (5623 1225);
DISPLAY INVISIBLE (5623 1225);
FORCEADD TAP..1
(5625 925);
FORCEPROP 3 LASTPIN (5575 925) SIG_NAME P5E_CPU1_PE1_RX_DP<15>
J 0
(5585 935);
DISPLAY 0.659574 (5585 935);
PAINT MONO (5585 935);
DISPLAY INVISIBLE (5585 935);
FORCEPROP 1 LASTPIN (5575 925) BN 15
J 0
(5563 933);
DISPLAY 0.680851 (5563 933);
PAINT GREEN (5563 933);
FORCEPROP 2 LAST CDS_LIB standard
J 0
(5625 925);
PAINT MONO (5625 925);
DISPLAY INVISIBLE (5625 925);
FORCEPROP 1 LAST BODY_TYPE PLUMBING
J 0
(5625 975);
DISPLAY 0.872340 (5625 975);
PAINT GREEN (5625 975);
DISPLAY INVISIBLE (5625 975);
FORCEPROP 1 LAST HDL_TAP TRUE
J 0
(5950 800);
DISPLAY 0.872340 (5950 800);
PAINT GREEN (5950 800);
DISPLAY INVISIBLE (5950 800);
FORCEPROP 1 LAST PATH I254
J 0
(5623 925);
DISPLAY 0.872340 (5623 925);
PAINT GREEN (5623 925);
DISPLAY INVISIBLE (5623 925);
FORCEADD TAP..1
(5625 1075);
FORCEPROP 3 LASTPIN (5575 1075) SIG_NAME P5E_CPU1_PE1_RX_DP<14>
J 0
(5585 1085);
DISPLAY 0.659574 (5585 1085);
PAINT MONO (5585 1085);
DISPLAY INVISIBLE (5585 1085);
FORCEPROP 1 LASTPIN (5575 1075) BN 14
J 0
(5563 1083);
DISPLAY 0.680851 (5563 1083);
PAINT GREEN (5563 1083);
FORCEPROP 2 LAST CDS_LIB standard
J 0
(5625 1075);
PAINT MONO (5625 1075);
DISPLAY INVISIBLE (5625 1075);
FORCEPROP 1 LAST BODY_TYPE PLUMBING
J 0
(5625 1125);
DISPLAY 0.872340 (5625 1125);
PAINT GREEN (5625 1125);
DISPLAY INVISIBLE (5625 1125);
FORCEPROP 1 LAST HDL_TAP TRUE
J 0
(5950 950);
DISPLAY 0.872340 (5950 950);
PAINT GREEN (5950 950);
DISPLAY INVISIBLE (5950 950);
FORCEPROP 1 LAST PATH I255
J 0
(5623 1075);
DISPLAY 0.872340 (5623 1075);
PAINT GREEN (5623 1075);
DISPLAY INVISIBLE (5623 1075);
FORCEADD UNIVERSAL_POWER..1
(3550 5500);
FORCEPROP 3 LASTPIN (3550 5450) SIG_NAME P12V_OCP_V3_2\g
J 0
(3560 5460);
DISPLAY 0.659574 (3560 5460);
PAINT MONO (3560 5460);
DISPLAY INVISIBLE (3560 5460);
FORCEPROP 1 LAST HDL_POWER P12V_OCP_V3_2
J 1
(3550 5550);
DISPLAY 0.872340 (3550 5550);
PAINT GREEN (3550 5550);
FORCEPROP 2 LAST CDS_LIB logical_power
J 0
(3550 5500);
DISPLAY INVISIBLE (3550 5500);
FORCEPROP 1 LAST PATH I257
J 0
(3600 5525);
DISPLAY 0.872340 (3600 5525);
PAINT AQUA (3600 5525);
DISPLAY INVISIBLE (3600 5525);
FORCEADD Q_RES..2
(300 350);
FORCEPROP 1 LAST PART_NUMBER CS24702FB06
J 0
(340 225);
DISPLAY 0.787234 (340 225);
DISPLAY INVISIBLE (340 225);
FORCEPROP 1 LAST WATTAGE 1/16W
J 0
(340 325);
DISPLAY 0.787234 (340 325);
FORCEPROP 1 LAST VALUE 4.7K
J 0
(345 425);
DISPLAY 0.787234 (345 425);
FORCEPROP 1 LAST PACK_TYPE 0402LF
J 0
(340 175);
DISPLAY 0.787234 (340 175);
FORCEPROP 1 LAST MATERIAL CHIP
J 0
(340 275);
DISPLAY 0.787234 (340 275);
FORCEPROP 1 LAST TOLERANCE 1%
J 0
(345 375);
DISPLAY 0.787234 (345 375);
FORCEPROP 1 LAST $LOCATION R3162
J 0
(345 475);
DISPLAY 0.978723 (345 475);
FORCEPROP 1 LASTPIN (300 450) $PN 1
J 0
(305 412);
DISPLAY 0.787234 (305 412);
FORCEPROP 1 LASTPIN (300 250) $PN 2
J 0
(305 260);
DISPLAY 0.787234 (305 260);
FORCEPROP 2 LAST CDS_LIB pure_quanta
J 0
(300 350);
PAINT MONO (300 350);
DISPLAY INVISIBLE (300 350);
FORCEPROP 1 LAST PATH I26
J 0
(350 525);
DISPLAY 0.978723 (350 525);
PAINT WHITE (350 525);
DISPLAY INVISIBLE (350 525);
FORCEPROP 2 LAST CDS_LOCATION R3162
J 0
(350 575);
DISPLAY 1.021277 (350 575);
DISPLAY INVISIBLE (350 575);
FORCEPROP 2 LAST $SEC 1
J 0
(350 575);
DISPLAY 0.680851 (350 575);
PAINT MONO (350 575);
DISPLAY INVISIBLE (350 575);
FORCEPROP 2 LAST CDS_SEC 1
J 0
(350 575);
DISPLAY 1.021277 (350 575);
DISPLAY INVISIBLE (350 575);
FORCEADD OFFPAGE..4
(6275 4525);
FORCEPROP 2 LAST $XR0 161 
J 0
(6461 4525);
DISPLAY 0.638298 (6461 4525);
PAINT MONO (6461 4525);
FORCEPROP 2 LAST CDS_LIB standard
J 0
(6275 4525);
PAINT MONO (6275 4525);
DISPLAY INVISIBLE (6275 4525);
FORCEPROP 1 LAST OFFPAGE TRUE
J 0
(6600 4400);
DISPLAY 0.872340 (6600 4400);
PAINT GREEN (6600 4400);
DISPLAY INVISIBLE (6600 4400);
FORCEPROP 1 LAST COMMENT_BODY TRUE
J 0
(6250 4425);
DISPLAY 0.872340 (6250 4425);
PAINT GREEN (6250 4425);
DISPLAY INVISIBLE (6250 4425);
FORCEPROP 2 LAST PATH I27
J 0
(6475 4575);
DISPLAY 1.021277 (6475 4575);
DISPLAY INVISIBLE (6475 4575);
FORCEADD OFFPAGE..1
(1025 3975);
FORCEPROP 2 LAST $XR0 160 
J 0
(743 3975);
DISPLAY 0.638298 (743 3975);
PAINT MONO (743 3975);
FORCEPROP 2 LAST CDS_LIB standard
J 0
(1025 3975);
PAINT MONO (1025 3975);
DISPLAY INVISIBLE (1025 3975);
FORCEPROP 1 LAST OFFPAGE TRUE
J 0
(1350 3850);
DISPLAY 0.872340 (1350 3850);
PAINT GREEN (1350 3850);
DISPLAY INVISIBLE (1350 3850);
FORCEPROP 1 LAST COMMENT_BODY TRUE
J 0
(1150 3875);
DISPLAY 0.872340 (1150 3875);
PAINT GREEN (1150 3875);
DISPLAY INVISIBLE (1150 3875);
FORCEPROP 2 LAST PATH I28
J 0
(775 4025);
DISPLAY 1.021277 (775 4025);
DISPLAY INVISIBLE (775 4025);
FORCEADD OFFPAGE..1
(1025 4075);
FORCEPROP 2 LAST $XR0 160 
J 0
(743 4075);
DISPLAY 0.638298 (743 4075);
PAINT MONO (743 4075);
FORCEPROP 2 LAST CDS_LIB standard
J 0
(1025 4075);
PAINT MONO (1025 4075);
DISPLAY INVISIBLE (1025 4075);
FORCEPROP 1 LAST OFFPAGE TRUE
J 0
(1350 3950);
DISPLAY 0.872340 (1350 3950);
PAINT GREEN (1350 3950);
DISPLAY INVISIBLE (1350 3950);
FORCEPROP 1 LAST COMMENT_BODY TRUE
J 0
(1150 3975);
DISPLAY 0.872340 (1150 3975);
PAINT GREEN (1150 3975);
DISPLAY INVISIBLE (1150 3975);
FORCEPROP 2 LAST PATH I29
J 0
(775 4125);
DISPLAY 1.021277 (775 4125);
DISPLAY INVISIBLE (775 4125);
FORCEADD OFFPAGE..5
(800 5175);
FORCEPROP 2 LAST $XR2 213 
J 0
(305 5175);
DISPLAY 0.638298 (305 5175);
PAINT MONO (305 5175);
FORCEPROP 2 LAST $XR1 160 
J 0
(425 5175);
DISPLAY 0.638298 (425 5175);
PAINT MONO (425 5175);
FORCEPROP 2 LAST $XR0 159 
J 0
(545 5175);
DISPLAY 0.638298 (545 5175);
PAINT MONO (545 5175);
FORCEPROP 2 LAST CDS_LIB standard
J 0
(800 5175);
DISPLAY INVISIBLE (800 5175);
FORCEPROP 1 LAST OFFPAGE TRUE
J 0
(1125 5050);
DISPLAY 0.872340 (1125 5050);
PAINT GREEN (1125 5050);
DISPLAY INVISIBLE (1125 5050);
FORCEPROP 1 LAST COMMENT_BODY TRUE
J 0
(900 5100);
DISPLAY 0.872340 (900 5100);
PAINT GREEN (900 5100);
DISPLAY INVISIBLE (900 5100);
FORCEPROP 2 LAST PATH I3
J 0
(550 5225);
DISPLAY 1.021277 (550 5225);
DISPLAY INVISIBLE (550 5225);
FORCEADD OFFPAGE..1
(1025 4025);
FORCEPROP 2 LAST $XR0 160 
J 0
(743 4025);
DISPLAY 0.638298 (743 4025);
PAINT MONO (743 4025);
FORCEPROP 2 LAST CDS_LIB standard
J 0
(1025 4025);
PAINT MONO (1025 4025);
DISPLAY INVISIBLE (1025 4025);
FORCEPROP 1 LAST OFFPAGE TRUE
J 0
(1350 3900);
DISPLAY 0.872340 (1350 3900);
PAINT GREEN (1350 3900);
DISPLAY INVISIBLE (1350 3900);
FORCEPROP 1 LAST COMMENT_BODY TRUE
J 0
(1150 3925);
DISPLAY 0.872340 (1150 3925);
PAINT GREEN (1150 3925);
DISPLAY INVISIBLE (1150 3925);
FORCEPROP 2 LAST PATH I30
J 0
(775 4075);
DISPLAY 1.021277 (775 4075);
DISPLAY INVISIBLE (775 4075);
FORCEADD SCONN168_ME1016810202011..1
(4500 2800);
FORCEPROP 1 LAST PART_NUMBER DFHSG8FR011
J 0
(4011 5420);
DISPLAY 0.723404 (4011 5420);
PAINT GREEN (4011 5420);
DISPLAY INVISIBLE (4011 5420);
FORCEPROP 2 LAST VALUE SCONN168_ME1016810202011
J 0
(4025 5625);
DISPLAY 1.021277 (4025 5625);
FORCEPROP 1 LAST MATERIAL IO
J 0
(4011 5293);
DISPLAY 0.723404 (4011 5293);
PAINT GREEN (4011 5293);
FORCEPROP 2 LAST PART_TYPE SMLF
J 0
(4025 5675);
DISPLAY 1.021277 (4025 5675);
FORCEPROP 1 LAST LOCATION J35
J 0
(4011 5567);
DISPLAY 0.723404 (4011 5567);
PAINT GREEN (4011 5567);
FORCEPROP 0 LASTPIN (3850 3875) $PN B11
J 2
(3840 3885);
DISPLAY 0.680851 (3840 3885);
PAINT MONO (3840 3885);
FORCEPROP 0 LASTPIN (3850 4375) $PN B1
J 2
(3840 4385);
DISPLAY 0.680851 (3840 4385);
PAINT MONO (3840 4385);
FORCEPROP 0 LASTPIN (3850 4325) $PN B2
J 2
(3840 4335);
DISPLAY 0.680851 (3840 4335);
PAINT MONO (3840 4335);
FORCEPROP 0 LASTPIN (3850 4275) $PN B3
J 2
(3840 4285);
DISPLAY 0.680851 (3840 4285);
PAINT MONO (3840 4285);
FORCEPROP 0 LASTPIN (3850 4225) $PN B4
J 2
(3840 4235);
DISPLAY 0.680851 (3840 4235);
PAINT MONO (3840 4235);
FORCEPROP 0 LASTPIN (3850 4175) $PN B5
J 2
(3840 4185);
DISPLAY 0.680851 (3840 4185);
PAINT MONO (3840 4185);
FORCEPROP 0 LASTPIN (3850 4125) $PN B6
J 2
(3840 4135);
DISPLAY 0.680851 (3840 4135);
PAINT MONO (3840 4135);
FORCEPROP 0 LASTPIN (3850 3825) $PN B12
J 2
(3840 3835);
DISPLAY 0.680851 (3840 3835);
PAINT MONO (3840 3835);
FORCEPROP 0 LASTPIN (3850 4075) $PN B7
J 2
(3840 4085);
DISPLAY 0.680851 (3840 4085);
PAINT MONO (3840 4085);
FORCEPROP 0 LASTPIN (3850 4025) $PN B8
J 2
(3840 4035);
DISPLAY 0.680851 (3840 4035);
PAINT MONO (3840 4035);
FORCEPROP 0 LASTPIN (3850 3975) $PN B9
J 2
(3840 3985);
DISPLAY 0.680851 (3840 3985);
PAINT MONO (3840 3985);
FORCEPROP 0 LASTPIN (3850 4925) $PN OB6
J 2
(3840 4935);
DISPLAY 0.680851 (3840 4935);
PAINT MONO (3840 4935);
FORCEPROP 0 LASTPIN (3850 5025) $PN OB4
J 2
(3840 5035);
DISPLAY 0.680851 (3840 5035);
PAINT MONO (3840 5035);
FORCEPROP 0 LASTPIN (3850 4975) $PN OB5
J 2
(3840 4985);
DISPLAY 0.680851 (3840 4985);
PAINT MONO (3840 4985);
FORCEPROP 0 LASTPIN (5150 625) $PN G1
J 0
(5160 635);
DISPLAY 0.680851 (5160 635);
PAINT MONO (5160 635);
FORCEPROP 0 LASTPIN (5150 575) $PN G2
J 0
(5160 585);
DISPLAY 0.680851 (5160 585);
PAINT MONO (5160 585);
FORCEPROP 0 LASTPIN (5150 525) $PN G3
J 0
(5160 535);
DISPLAY 0.680851 (5160 535);
PAINT MONO (5160 535);
FORCEPROP 0 LASTPIN (5150 475) $PN G4
J 0
(5160 485);
DISPLAY 0.680851 (5160 485);
PAINT MONO (5160 485);
FORCEPROP 0 LASTPIN (5150 425) $PN G5
J 0
(5160 435);
DISPLAY 0.680851 (5160 435);
PAINT MONO (5160 435);
FORCEPROP 0 LASTPIN (5150 4375) $PN A1
J 0
(5160 4385);
DISPLAY 0.680851 (5160 4385);
PAINT MONO (5160 4385);
FORCEPROP 0 LASTPIN (5150 4325) $PN A2
J 0
(5160 4335);
DISPLAY 0.680851 (5160 4335);
PAINT MONO (5160 4335);
FORCEPROP 0 LASTPIN (5150 4275) $PN A3
J 0
(5160 4285);
DISPLAY 0.680851 (5160 4285);
PAINT MONO (5160 4285);
FORCEPROP 0 LASTPIN (5150 4225) $PN A4
J 0
(5160 4235);
DISPLAY 0.680851 (5160 4235);
PAINT MONO (5160 4235);
FORCEPROP 0 LASTPIN (5150 4175) $PN A5
J 0
(5160 4185);
DISPLAY 0.680851 (5160 4185);
PAINT MONO (5160 4185);
FORCEPROP 0 LASTPIN (5150 4125) $PN A6
J 0
(5160 4135);
DISPLAY 0.680851 (5160 4135);
PAINT MONO (5160 4135);
FORCEPROP 0 LASTPIN (5150 3775) $PN A13
J 0
(5160 3785);
DISPLAY 0.680851 (5160 3785);
PAINT MONO (5160 3785);
FORCEPROP 0 LASTPIN (5150 3625) $PN A16
J 0
(5160 3635);
DISPLAY 0.680851 (5160 3635);
PAINT MONO (5160 3635);
FORCEPROP 0 LASTPIN (5150 3475) $PN A19
J 0
(5160 3485);
DISPLAY 0.680851 (5160 3485);
PAINT MONO (5160 3485);
FORCEPROP 0 LASTPIN (5150 3325) $PN A22
J 0
(5160 3335);
DISPLAY 0.680851 (5160 3335);
PAINT MONO (5160 3335);
FORCEPROP 0 LASTPIN (5150 3175) $PN A25
J 0
(5160 3185);
DISPLAY 0.680851 (5160 3185);
PAINT MONO (5160 3185);
FORCEPROP 0 LASTPIN (5150 3025) $PN A28
J 0
(5160 3035);
DISPLAY 0.680851 (5160 3035);
PAINT MONO (5160 3035);
FORCEPROP 0 LASTPIN (5150 2875) $PN A29
J 0
(5160 2885);
DISPLAY 0.680851 (5160 2885);
PAINT MONO (5160 2885);
FORCEPROP 0 LASTPIN (5150 2725) $PN A32
J 0
(5160 2735);
DISPLAY 0.680851 (5160 2735);
PAINT MONO (5160 2735);
FORCEPROP 0 LASTPIN (5150 2575) $PN A35
J 0
(5160 2585);
DISPLAY 0.680851 (5160 2585);
PAINT MONO (5160 2585);
FORCEPROP 0 LASTPIN (5150 2425) $PN A38
J 0
(5160 2435);
DISPLAY 0.680851 (5160 2435);
PAINT MONO (5160 2435);
FORCEPROP 0 LASTPIN (5150 2275) $PN A41
J 0
(5160 2285);
DISPLAY 0.680851 (5160 2285);
PAINT MONO (5160 2285);
FORCEPROP 0 LASTPIN (5150 2075) $PN A43
J 0
(5160 2085);
DISPLAY 0.680851 (5160 2085);
PAINT MONO (5160 2085);
FORCEPROP 0 LASTPIN (5150 1925) $PN A46
J 0
(5160 1935);
DISPLAY 0.680851 (5160 1935);
PAINT MONO (5160 1935);
FORCEPROP 0 LASTPIN (5150 1775) $PN A49
J 0
(5160 1785);
DISPLAY 0.680851 (5160 1785);
PAINT MONO (5160 1785);
FORCEPROP 0 LASTPIN (5150 1625) $PN A52
J 0
(5160 1635);
DISPLAY 0.680851 (5160 1635);
PAINT MONO (5160 1635);
FORCEPROP 0 LASTPIN (5150 1475) $PN A55
J 0
(5160 1485);
DISPLAY 0.680851 (5160 1485);
PAINT MONO (5160 1485);
FORCEPROP 0 LASTPIN (5150 1325) $PN A58
J 0
(5160 1335);
DISPLAY 0.680851 (5160 1335);
PAINT MONO (5160 1335);
FORCEPROP 0 LASTPIN (5150 1175) $PN A61
J 0
(5160 1185);
DISPLAY 0.680851 (5160 1185);
PAINT MONO (5160 1185);
FORCEPROP 0 LASTPIN (5150 1025) $PN A64
J 0
(5160 1035);
DISPLAY 0.680851 (5160 1035);
PAINT MONO (5160 1035);
FORCEPROP 0 LASTPIN (5150 875) $PN A67
J 0
(5160 885);
DISPLAY 0.680851 (5160 885);
PAINT MONO (5160 885);
FORCEPROP 0 LASTPIN (3850 3775) $PN B13
J 2
(3840 3785);
DISPLAY 0.680851 (3840 3785);
PAINT MONO (3840 3785);
FORCEPROP 0 LASTPIN (3850 3625) $PN B16
J 2
(3840 3635);
DISPLAY 0.680851 (3840 3635);
PAINT MONO (3840 3635);
FORCEPROP 0 LASTPIN (3850 3475) $PN B19
J 2
(3840 3485);
DISPLAY 0.680851 (3840 3485);
PAINT MONO (3840 3485);
FORCEPROP 0 LASTPIN (3850 3325) $PN B22
J 2
(3840 3335);
DISPLAY 0.680851 (3840 3335);
PAINT MONO (3840 3335);
FORCEPROP 0 LASTPIN (3850 3175) $PN B25
J 2
(3840 3185);
DISPLAY 0.680851 (3840 3185);
PAINT MONO (3840 3185);
FORCEPROP 0 LASTPIN (3850 3025) $PN B28
J 2
(3840 3035);
DISPLAY 0.680851 (3840 3035);
PAINT MONO (3840 3035);
FORCEPROP 0 LASTPIN (3850 2875) $PN B29
J 2
(3840 2885);
DISPLAY 0.680851 (3840 2885);
PAINT MONO (3840 2885);
FORCEPROP 0 LASTPIN (3850 2725) $PN B32
J 2
(3840 2735);
DISPLAY 0.680851 (3840 2735);
PAINT MONO (3840 2735);
FORCEPROP 0 LASTPIN (3850 2575) $PN B35
J 2
(3840 2585);
DISPLAY 0.680851 (3840 2585);
PAINT MONO (3840 2585);
FORCEPROP 0 LASTPIN (3850 2425) $PN B38
J 2
(3840 2435);
DISPLAY 0.680851 (3840 2435);
PAINT MONO (3840 2435);
FORCEPROP 0 LASTPIN (3850 2275) $PN B41
J 2
(3840 2285);
DISPLAY 0.680851 (3840 2285);
PAINT MONO (3840 2285);
FORCEPROP 0 LASTPIN (3850 2075) $PN B43
J 2
(3840 2085);
DISPLAY 0.680851 (3840 2085);
PAINT MONO (3840 2085);
FORCEPROP 0 LASTPIN (3850 1925) $PN B46
J 2
(3840 1935);
DISPLAY 0.680851 (3840 1935);
PAINT MONO (3840 1935);
FORCEPROP 0 LASTPIN (3850 1775) $PN B49
J 2
(3840 1785);
DISPLAY 0.680851 (3840 1785);
PAINT MONO (3840 1785);
FORCEPROP 0 LASTPIN (3850 1625) $PN B52
J 2
(3840 1635);
DISPLAY 0.680851 (3840 1635);
PAINT MONO (3840 1635);
FORCEPROP 0 LASTPIN (3850 1475) $PN B55
J 2
(3840 1485);
DISPLAY 0.680851 (3840 1485);
PAINT MONO (3840 1485);
FORCEPROP 0 LASTPIN (3850 1325) $PN B58
J 2
(3840 1335);
DISPLAY 0.680851 (3840 1335);
PAINT MONO (3840 1335);
FORCEPROP 0 LASTPIN (3850 1175) $PN B61
J 2
(3840 1185);
DISPLAY 0.680851 (3840 1185);
PAINT MONO (3840 1185);
FORCEPROP 0 LASTPIN (3850 1025) $PN B64
J 2
(3840 1035);
DISPLAY 0.680851 (3840 1035);
PAINT MONO (3840 1035);
FORCEPROP 0 LASTPIN (3850 875) $PN B67
J 2
(3840 885);
DISPLAY 0.680851 (3840 885);
PAINT MONO (3840 885);
FORCEPROP 0 LASTPIN (5150 4725) $PN OA10
J 0
(5160 4735);
DISPLAY 0.680851 (5160 4735);
PAINT MONO (5160 4735);
FORCEPROP 0 LASTPIN (5150 4575) $PN OA13
J 0
(5160 4585);
DISPLAY 0.680851 (5160 4585);
PAINT MONO (5160 4585);
FORCEPROP 0 LASTPIN (3850 4725) $PN OB10
J 2
(3840 4735);
DISPLAY 0.680851 (3840 4735);
PAINT MONO (3840 4735);
FORCEPROP 0 LASTPIN (3850 4575) $PN OB13
J 2
(3840 4585);
DISPLAY 0.680851 (3840 4585);
PAINT MONO (3840 4585);
FORCEPROP 0 LASTPIN (3850 5075) $PN OB3
J 2
(3840 5085);
DISPLAY 0.680851 (3840 5085);
PAINT MONO (3840 5085);
FORCEPROP 0 LASTPIN (3850 5125) $PN OB2
J 2
(3840 5135);
DISPLAY 0.680851 (3840 5135);
PAINT MONO (3840 5135);
FORCEPROP 0 LASTPIN (3850 5175) $PN OB1
J 2
(3840 5185);
DISPLAY 0.680851 (3840 5185);
PAINT MONO (3840 5185);
FORCEPROP 0 LASTPIN (5150 3575) $PN A17
J 0
(5160 3585);
DISPLAY 0.680851 (5160 3585);
PAINT MONO (5160 3585);
FORCEPROP 0 LASTPIN (5150 3425) $PN A20
J 0
(5160 3435);
DISPLAY 0.680851 (5160 3435);
PAINT MONO (5160 3435);
FORCEPROP 0 LASTPIN (5150 3275) $PN A23
J 0
(5160 3285);
DISPLAY 0.680851 (5160 3285);
PAINT MONO (5160 3285);
FORCEPROP 0 LASTPIN (5150 3125) $PN A26
J 0
(5160 3135);
DISPLAY 0.680851 (5160 3135);
PAINT MONO (5160 3135);
FORCEPROP 0 LASTPIN (5150 2825) $PN A30
J 0
(5160 2835);
DISPLAY 0.680851 (5160 2835);
PAINT MONO (5160 2835);
FORCEPROP 0 LASTPIN (5150 2675) $PN A33
J 0
(5160 2685);
DISPLAY 0.680851 (5160 2685);
PAINT MONO (5160 2685);
FORCEPROP 0 LASTPIN (5150 2525) $PN A36
J 0
(5160 2535);
DISPLAY 0.680851 (5160 2535);
PAINT MONO (5160 2535);
FORCEPROP 0 LASTPIN (5150 2375) $PN A39
J 0
(5160 2385);
DISPLAY 0.680851 (5160 2385);
PAINT MONO (5160 2385);
FORCEPROP 0 LASTPIN (5150 2025) $PN A44
J 0
(5160 2035);
DISPLAY 0.680851 (5160 2035);
PAINT MONO (5160 2035);
FORCEPROP 0 LASTPIN (5150 1875) $PN A47
J 0
(5160 1885);
DISPLAY 0.680851 (5160 1885);
PAINT MONO (5160 1885);
FORCEPROP 0 LASTPIN (5150 1725) $PN A50
J 0
(5160 1735);
DISPLAY 0.680851 (5160 1735);
PAINT MONO (5160 1735);
FORCEPROP 0 LASTPIN (5150 1575) $PN A53
J 0
(5160 1585);
DISPLAY 0.680851 (5160 1585);
PAINT MONO (5160 1585);
FORCEPROP 0 LASTPIN (5150 1425) $PN A56
J 0
(5160 1435);
DISPLAY 0.680851 (5160 1435);
PAINT MONO (5160 1435);
FORCEPROP 0 LASTPIN (5150 1275) $PN A59
J 0
(5160 1285);
DISPLAY 0.680851 (5160 1285);
PAINT MONO (5160 1285);
FORCEPROP 0 LASTPIN (5150 1125) $PN A62
J 0
(5160 1135);
DISPLAY 0.680851 (5160 1135);
PAINT MONO (5160 1135);
FORCEPROP 0 LASTPIN (5150 975) $PN A65
J 0
(5160 985);
DISPLAY 0.680851 (5160 985);
PAINT MONO (5160 985);
FORCEPROP 0 LASTPIN (5150 3525) $PN A18
J 0
(5160 3535);
DISPLAY 0.680851 (5160 3535);
PAINT MONO (5160 3535);
FORCEPROP 0 LASTPIN (5150 3375) $PN A21
J 0
(5160 3385);
DISPLAY 0.680851 (5160 3385);
PAINT MONO (5160 3385);
FORCEPROP 0 LASTPIN (5150 3225) $PN A24
J 0
(5160 3235);
DISPLAY 0.680851 (5160 3235);
PAINT MONO (5160 3235);
FORCEPROP 0 LASTPIN (5150 3075) $PN A27
J 0
(5160 3085);
DISPLAY 0.680851 (5160 3085);
PAINT MONO (5160 3085);
FORCEPROP 0 LASTPIN (5150 2775) $PN A31
J 0
(5160 2785);
DISPLAY 0.680851 (5160 2785);
PAINT MONO (5160 2785);
FORCEPROP 0 LASTPIN (5150 2625) $PN A34
J 0
(5160 2635);
DISPLAY 0.680851 (5160 2635);
PAINT MONO (5160 2635);
FORCEPROP 0 LASTPIN (5150 2475) $PN A37
J 0
(5160 2485);
DISPLAY 0.680851 (5160 2485);
PAINT MONO (5160 2485);
FORCEPROP 0 LASTPIN (5150 2325) $PN A40
J 0
(5160 2335);
DISPLAY 0.680851 (5160 2335);
PAINT MONO (5160 2335);
FORCEPROP 0 LASTPIN (5150 1975) $PN A45
J 0
(5160 1985);
DISPLAY 0.680851 (5160 1985);
PAINT MONO (5160 1985);
FORCEPROP 0 LASTPIN (5150 1825) $PN A48
J 0
(5160 1835);
DISPLAY 0.680851 (5160 1835);
PAINT MONO (5160 1835);
FORCEPROP 0 LASTPIN (5150 1675) $PN A51
J 0
(5160 1685);
DISPLAY 0.680851 (5160 1685);
PAINT MONO (5160 1685);
FORCEPROP 0 LASTPIN (5150 1525) $PN A54
J 0
(5160 1535);
DISPLAY 0.680851 (5160 1535);
PAINT MONO (5160 1535);
FORCEPROP 0 LASTPIN (5150 1375) $PN A57
J 0
(5160 1385);
DISPLAY 0.680851 (5160 1385);
PAINT MONO (5160 1385);
FORCEPROP 0 LASTPIN (5150 1225) $PN A60
J 0
(5160 1235);
DISPLAY 0.680851 (5160 1235);
PAINT MONO (5160 1235);
FORCEPROP 0 LASTPIN (5150 1075) $PN A63
J 0
(5160 1085);
DISPLAY 0.680851 (5160 1085);
PAINT MONO (5160 1085);
FORCEPROP 0 LASTPIN (5150 925) $PN A66
J 0
(5160 935);
DISPLAY 0.680851 (5160 935);
PAINT MONO (5160 935);
FORCEPROP 0 LASTPIN (3850 3925) $PN B10
J 2
(3840 3935);
DISPLAY 0.680851 (3840 3935);
PAINT MONO (3840 3935);
FORCEPROP 0 LASTPIN (5150 3875) $PN A11
J 0
(5160 3885);
DISPLAY 0.680851 (5160 3885);
PAINT MONO (5160 3885);
FORCEPROP 0 LASTPIN (5150 5175) $PN OA1
J 0
(5160 5185);
DISPLAY 0.680851 (5160 5185);
PAINT MONO (5160 5185);
FORCEPROP 0 LASTPIN (5150 5125) $PN OA2
J 0
(5160 5135);
DISPLAY 0.680851 (5160 5135);
PAINT MONO (5160 5135);
FORCEPROP 0 LASTPIN (3850 3575) $PN B17
J 2
(3840 3585);
DISPLAY 0.680851 (3840 3585);
PAINT MONO (3840 3585);
FORCEPROP 0 LASTPIN (3850 3425) $PN B20
J 2
(3840 3435);
DISPLAY 0.680851 (3840 3435);
PAINT MONO (3840 3435);
FORCEPROP 0 LASTPIN (3850 3275) $PN B23
J 2
(3840 3285);
DISPLAY 0.680851 (3840 3285);
PAINT MONO (3840 3285);
FORCEPROP 0 LASTPIN (3850 3125) $PN B26
J 2
(3840 3135);
DISPLAY 0.680851 (3840 3135);
PAINT MONO (3840 3135);
FORCEPROP 0 LASTPIN (3850 2825) $PN B30
J 2
(3840 2835);
DISPLAY 0.680851 (3840 2835);
PAINT MONO (3840 2835);
FORCEPROP 0 LASTPIN (3850 2675) $PN B33
J 2
(3840 2685);
DISPLAY 0.680851 (3840 2685);
PAINT MONO (3840 2685);
FORCEPROP 0 LASTPIN (3850 2525) $PN B36
J 2
(3840 2535);
DISPLAY 0.680851 (3840 2535);
PAINT MONO (3840 2535);
FORCEPROP 0 LASTPIN (3850 2375) $PN B39
J 2
(3840 2385);
DISPLAY 0.680851 (3840 2385);
PAINT MONO (3840 2385);
FORCEPROP 0 LASTPIN (3850 2025) $PN B44
J 2
(3840 2035);
DISPLAY 0.680851 (3840 2035);
PAINT MONO (3840 2035);
FORCEPROP 0 LASTPIN (3850 1875) $PN B47
J 2
(3840 1885);
DISPLAY 0.680851 (3840 1885);
PAINT MONO (3840 1885);
FORCEPROP 0 LASTPIN (3850 1725) $PN B50
J 2
(3840 1735);
DISPLAY 0.680851 (3840 1735);
PAINT MONO (3840 1735);
FORCEPROP 0 LASTPIN (3850 1575) $PN B53
J 2
(3840 1585);
DISPLAY 0.680851 (3840 1585);
PAINT MONO (3840 1585);
FORCEPROP 0 LASTPIN (3850 1425) $PN B56
J 2
(3840 1435);
DISPLAY 0.680851 (3840 1435);
PAINT MONO (3840 1435);
FORCEPROP 0 LASTPIN (3850 1275) $PN B59
J 2
(3840 1285);
DISPLAY 0.680851 (3840 1285);
PAINT MONO (3840 1285);
FORCEPROP 0 LASTPIN (3850 1125) $PN B62
J 2
(3840 1135);
DISPLAY 0.680851 (3840 1135);
PAINT MONO (3840 1135);
FORCEPROP 0 LASTPIN (3850 975) $PN B65
J 2
(3840 985);
DISPLAY 0.680851 (3840 985);
PAINT MONO (3840 985);
FORCEPROP 0 LASTPIN (3850 3525) $PN B18
J 2
(3840 3535);
DISPLAY 0.680851 (3840 3535);
PAINT MONO (3840 3535);
FORCEPROP 0 LASTPIN (3850 3375) $PN B21
J 2
(3840 3385);
DISPLAY 0.680851 (3840 3385);
PAINT MONO (3840 3385);
FORCEPROP 0 LASTPIN (3850 3225) $PN B24
J 2
(3840 3235);
DISPLAY 0.680851 (3840 3235);
PAINT MONO (3840 3235);
FORCEPROP 0 LASTPIN (3850 3075) $PN B27
J 2
(3840 3085);
DISPLAY 0.680851 (3840 3085);
PAINT MONO (3840 3085);
FORCEPROP 0 LASTPIN (3850 2775) $PN B31
J 2
(3840 2785);
DISPLAY 0.680851 (3840 2785);
PAINT MONO (3840 2785);
FORCEPROP 0 LASTPIN (3850 2625) $PN B34
J 2
(3840 2635);
DISPLAY 0.680851 (3840 2635);
PAINT MONO (3840 2635);
FORCEPROP 0 LASTPIN (3850 2475) $PN B37
J 2
(3840 2485);
DISPLAY 0.680851 (3840 2485);
PAINT MONO (3840 2485);
FORCEPROP 0 LASTPIN (3850 2325) $PN B40
J 2
(3840 2335);
DISPLAY 0.680851 (3840 2335);
PAINT MONO (3840 2335);
FORCEPROP 0 LASTPIN (3850 1975) $PN B45
J 2
(3840 1985);
DISPLAY 0.680851 (3840 1985);
PAINT MONO (3840 1985);
FORCEPROP 0 LASTPIN (3850 1825) $PN B48
J 2
(3840 1835);
DISPLAY 0.680851 (3840 1835);
PAINT MONO (3840 1835);
FORCEPROP 0 LASTPIN (3850 1675) $PN B51
J 2
(3840 1685);
DISPLAY 0.680851 (3840 1685);
PAINT MONO (3840 1685);
FORCEPROP 0 LASTPIN (3850 1525) $PN B54
J 2
(3840 1535);
DISPLAY 0.680851 (3840 1535);
PAINT MONO (3840 1535);
FORCEPROP 0 LASTPIN (3850 1375) $PN B57
J 2
(3840 1385);
DISPLAY 0.680851 (3840 1385);
PAINT MONO (3840 1385);
FORCEPROP 0 LASTPIN (3850 1225) $PN B60
J 2
(3840 1235);
DISPLAY 0.680851 (3840 1235);
PAINT MONO (3840 1235);
FORCEPROP 0 LASTPIN (3850 1075) $PN B63
J 2
(3840 1085);
DISPLAY 0.680851 (3840 1085);
PAINT MONO (3840 1085);
FORCEPROP 0 LASTPIN (3850 925) $PN B66
J 2
(3840 935);
DISPLAY 0.680851 (3840 935);
PAINT MONO (3840 935);
FORCEPROP 0 LASTPIN (5150 3925) $PN A10
J 0
(5160 3935);
DISPLAY 0.680851 (5160 3935);
PAINT MONO (5160 3935);
FORCEPROP 0 LASTPIN (3850 2225) $PN B42
J 2
(3840 2235);
DISPLAY 0.680851 (3840 2235);
PAINT MONO (3840 2235);
FORCEPROP 0 LASTPIN (5150 2225) $PN A42
J 0
(5160 2235);
DISPLAY 0.680851 (5160 2235);
PAINT MONO (5160 2235);
FORCEPROP 0 LASTPIN (5150 3825) $PN A12
J 0
(5160 3835);
DISPLAY 0.680851 (5160 3835);
PAINT MONO (5160 3835);
FORCEPROP 0 LASTPIN (3850 725) $PN B70
J 2
(3840 735);
DISPLAY 0.680851 (3840 735);
PAINT MONO (3840 735);
FORCEPROP 0 LASTPIN (5150 725) $PN A70
J 0
(5160 735);
DISPLAY 0.680851 (5160 735);
PAINT MONO (5160 735);
FORCEPROP 0 LASTPIN (5150 5025) $PN OA4
J 0
(5160 5035);
DISPLAY 0.680851 (5160 5035);
PAINT MONO (5160 5035);
FORCEPROP 0 LASTPIN (5150 4975) $PN OA5
J 0
(5160 4985);
DISPLAY 0.680851 (5160 4985);
PAINT MONO (5160 4985);
FORCEPROP 0 LASTPIN (5150 4525) $PN OA14
J 0
(5160 4535);
DISPLAY 0.680851 (5160 4535);
PAINT MONO (5160 4535);
FORCEPROP 0 LASTPIN (3850 4525) $PN OB14
J 2
(3840 4535);
DISPLAY 0.680851 (3840 4535);
PAINT MONO (3840 4535);
FORCEPROP 0 LASTPIN (3850 4775) $PN OB9
J 2
(3840 4785);
DISPLAY 0.680851 (3840 4785);
PAINT MONO (3840 4785);
FORCEPROP 0 LASTPIN (3850 4825) $PN OB8
J 2
(3840 4835);
DISPLAY 0.680851 (3840 4835);
PAINT MONO (3840 4835);
FORCEPROP 0 LASTPIN (5150 4875) $PN OA7
J 0
(5160 4885);
DISPLAY 0.680851 (5160 4885);
PAINT MONO (5160 4885);
FORCEPROP 0 LASTPIN (5150 4775) $PN OA9
J 0
(5160 4785);
DISPLAY 0.680851 (5160 4785);
PAINT MONO (5160 4785);
FORCEPROP 0 LASTPIN (5150 4825) $PN OA8
J 0
(5160 4835);
DISPLAY 0.680851 (5160 4835);
PAINT MONO (5160 4835);
FORCEPROP 0 LASTPIN (3850 3725) $PN B14
J 2
(3840 3735);
DISPLAY 0.680851 (3840 3735);
PAINT MONO (3840 3735);
FORCEPROP 0 LASTPIN (5150 3725) $PN A14
J 0
(5160 3735);
DISPLAY 0.680851 (5160 3735);
PAINT MONO (5160 3735);
FORCEPROP 0 LASTPIN (3850 4675) $PN OB11
J 2
(3840 4685);
DISPLAY 0.680851 (3840 4685);
PAINT MONO (3840 4685);
FORCEPROP 0 LASTPIN (5150 4675) $PN OA11
J 0
(5160 4685);
DISPLAY 0.680851 (5160 4685);
PAINT MONO (5160 4685);
FORCEPROP 0 LASTPIN (3850 3675) $PN B15
J 2
(3840 3685);
DISPLAY 0.680851 (3840 3685);
PAINT MONO (3840 3685);
FORCEPROP 0 LASTPIN (5150 3675) $PN A15
J 0
(5160 3685);
DISPLAY 0.680851 (5160 3685);
PAINT MONO (5160 3685);
FORCEPROP 0 LASTPIN (3850 4625) $PN OB12
J 2
(3840 4635);
DISPLAY 0.680851 (3840 4635);
PAINT MONO (3840 4635);
FORCEPROP 0 LASTPIN (5150 4625) $PN OA12
J 0
(5160 4635);
DISPLAY 0.680851 (5160 4635);
PAINT MONO (5160 4635);
FORCEPROP 0 LASTPIN (3850 825) $PN B68
J 2
(3840 835);
DISPLAY 0.680851 (3840 835);
PAINT MONO (3840 835);
FORCEPROP 0 LASTPIN (3850 775) $PN B69
J 2
(3840 785);
DISPLAY 0.680851 (3840 785);
PAINT MONO (3840 785);
FORCEPROP 0 LASTPIN (3850 4875) $PN OB7
J 2
(3840 4885);
DISPLAY 0.680851 (3840 4885);
PAINT MONO (3840 4885);
FORCEPROP 0 LASTPIN (5150 4925) $PN OA6
J 0
(5160 4935);
DISPLAY 0.680851 (5160 4935);
PAINT MONO (5160 4935);
FORCEPROP 0 LASTPIN (5150 4075) $PN A7
J 0
(5160 4085);
DISPLAY 0.680851 (5160 4085);
PAINT MONO (5160 4085);
FORCEPROP 0 LASTPIN (5150 4025) $PN A8
J 0
(5160 4035);
DISPLAY 0.680851 (5160 4035);
PAINT MONO (5160 4035);
FORCEPROP 0 LASTPIN (5150 3975) $PN A9
J 0
(5160 3985);
DISPLAY 0.680851 (5160 3985);
PAINT MONO (5160 3985);
FORCEPROP 0 LASTPIN (5150 825) $PN A68
J 0
(5160 835);
DISPLAY 0.680851 (5160 835);
PAINT MONO (5160 835);
FORCEPROP 0 LASTPIN (5150 775) $PN A69
J 0
(5160 785);
DISPLAY 0.680851 (5160 785);
PAINT MONO (5160 785);
FORCEPROP 0 LASTPIN (5150 5075) $PN OA3
J 0
(5160 5085);
DISPLAY 0.680851 (5160 5085);
PAINT MONO (5160 5085);
FORCEPROP 1 LAST NEEDS_NO_SIZE TRUE
J 0
(4500 2800);
DISPLAY 0.723404 (4500 2800);
PAINT GREEN (4500 2800);
DISPLAY INVISIBLE (4500 2800);
FORCEPROP 1 LAST CDS_LMAN_SYM_OUTLINE -500,2475,500,-2475
J 0
(4500 2800);
DISPLAY 0.468085 (4500 2800);
PAINT GREEN (4500 2800);
DISPLAY INVISIBLE (4500 2800);
FORCEPROP 2 LAST CDS_LIB pure_quanta
J 0
(4500 2800);
DISPLAY INVISIBLE (4500 2800);
FORCEPROP 1 LAST PATH I303
J 0
(4500 2800);
DISPLAY 0.723404 (4500 2800);
PAINT GREEN (4500 2800);
DISPLAY INVISIBLE (4500 2800);
FORCEPROP 0 LAST $SEC 1
J 0
(4025 5725);
DISPLAY 0.680851 (4025 5725);
PAINT MONO (4025 5725);
DISPLAY INVISIBLE (4025 5725);
FORCEPROP 0 LAST CDS_SEC 1
J 0
(4025 5725);
DISPLAY 1.021277 (4025 5725);
DISPLAY INVISIBLE (4025 5725);
FORCEADD TAP..1
R 2
(3275 975);
FORCEPROP 3 LASTPIN (3325 975) SIG_NAME P5E_CPU1_PE1_TX_C_DN<15>
J 0
(3335 985);
DISPLAY 0.659574 (3335 985);
PAINT MONO (3335 985);
DISPLAY INVISIBLE (3335 985);
FORCEPROP 1 LASTPIN (3325 975) BN 15
J 2
(3337 983);
DISPLAY 0.680851 (3337 983);
PAINT GREEN (3337 983);
FORCEPROP 2 LAST CDS_LIB standard
J 0
(3275 975);
PAINT MONO (3275 975);
DISPLAY INVISIBLE (3275 975);
FORCEPROP 1 LAST BODY_TYPE PLUMBING
J 2
(3275 1025);
DISPLAY 0.872340 (3275 1025);
PAINT GREEN (3275 1025);
DISPLAY INVISIBLE (3275 1025);
FORCEPROP 1 LAST HDL_TAP TRUE
J 2
(2950 850);
DISPLAY 0.872340 (2950 850);
PAINT GREEN (2950 850);
DISPLAY INVISIBLE (2950 850);
FORCEPROP 1 LAST PATH I306
J 2
(3277 975);
DISPLAY 0.872340 (3277 975);
PAINT GREEN (3277 975);
DISPLAY INVISIBLE (3277 975);
FORCEADD TAP..1
R 2
(3125 925);
FORCEPROP 3 LASTPIN (3175 925) SIG_NAME P5E_CPU1_PE1_TX_C_DP<15>
J 0
(3185 935);
DISPLAY 0.659574 (3185 935);
PAINT MONO (3185 935);
DISPLAY INVISIBLE (3185 935);
FORCEPROP 1 LASTPIN (3175 925) BN 15
J 2
(3187 933);
DISPLAY 0.680851 (3187 933);
PAINT GREEN (3187 933);
FORCEPROP 2 LAST CDS_LIB standard
J 0
(3125 925);
PAINT MONO (3125 925);
DISPLAY INVISIBLE (3125 925);
FORCEPROP 1 LAST BODY_TYPE PLUMBING
J 2
(3125 975);
DISPLAY 0.872340 (3125 975);
PAINT GREEN (3125 975);
DISPLAY INVISIBLE (3125 975);
FORCEPROP 1 LAST HDL_TAP TRUE
J 2
(2800 800);
DISPLAY 0.872340 (2800 800);
PAINT GREEN (2800 800);
DISPLAY INVISIBLE (2800 800);
FORCEPROP 1 LAST PATH I307
J 2
(3127 925);
DISPLAY 0.872340 (3127 925);
PAINT GREEN (3127 925);
DISPLAY INVISIBLE (3127 925);
FORCEADD TAP..1
R 2
(3275 1275);
FORCEPROP 3 LASTPIN (3325 1275) SIG_NAME P5E_CPU1_PE1_TX_C_DN<13>
J 0
(3335 1285);
DISPLAY 0.659574 (3335 1285);
PAINT MONO (3335 1285);
DISPLAY INVISIBLE (3335 1285);
FORCEPROP 1 LASTPIN (3325 1275) BN 13
J 2
(3337 1283);
DISPLAY 0.680851 (3337 1283);
PAINT GREEN (3337 1283);
FORCEPROP 2 LAST CDS_LIB standard
J 0
(3275 1275);
PAINT MONO (3275 1275);
DISPLAY INVISIBLE (3275 1275);
FORCEPROP 1 LAST BODY_TYPE PLUMBING
J 2
(3275 1325);
DISPLAY 0.872340 (3275 1325);
PAINT GREEN (3275 1325);
DISPLAY INVISIBLE (3275 1325);
FORCEPROP 1 LAST HDL_TAP TRUE
J 2
(2950 1150);
DISPLAY 0.872340 (2950 1150);
PAINT GREEN (2950 1150);
DISPLAY INVISIBLE (2950 1150);
FORCEPROP 1 LAST PATH I309
J 2
(3277 1275);
DISPLAY 0.872340 (3277 1275);
PAINT GREEN (3277 1275);
DISPLAY INVISIBLE (3277 1275);
FORCEADD Q_RES..1
(1975 3975);
FORCEPROP 1 LAST PART_NUMBER CS00002JB13
J 0
(1850 4050);
DISPLAY 0.638298 (1850 4050);
DISPLAY INVISIBLE (1850 4050);
FORCEPROP 1 LAST TOLERANCE 5%
J 0
(2175 3975);
DISPLAY 0.638298 (2175 3975);
FORCEPROP 1 LAST VALUE 0
J 2
(2150 3975);
DISPLAY 0.638298 (2150 3975);
FORCEPROP 1 LAST PACK_TYPE 0402LF
J 0
(2250 3975);
DISPLAY 0.638298 (2250 3975);
FORCEPROP 1 LAST $LOCATION R3171
J 0
(1750 3975);
DISPLAY 0.787234 (1750 3975);
FORCEPROP 1 LASTPIN (1875 3975) $PN 1
J 0
(1887 3987);
DISPLAY 0.787234 (1887 3987);
FORCEPROP 1 LASTPIN (2075 3975) $PN 2
J 0
(2037 3987);
DISPLAY 0.787234 (2037 3987);
FORCEPROP 2 LAST CDS_LIB pure_quanta
J 0
(1975 3975);
PAINT MONO (1975 3975);
DISPLAY INVISIBLE (1975 3975);
FORCEPROP 1 LAST MATERIAL CHIP
J 0
(1850 4100);
DISPLAY 0.638298 (1850 4100);
DISPLAY INVISIBLE (1850 4100);
FORCEPROP 1 LAST WATTAGE 1/16W
J 2
(2150 4100);
DISPLAY 0.638298 (2150 4100);
DISPLAY INVISIBLE (2150 4100);
FORCEPROP 1 LAST PATH I31
J 0
(1925 4125);
DISPLAY 0.978723 (1925 4125);
PAINT WHITE (1925 4125);
DISPLAY INVISIBLE (1925 4125);
FORCEPROP 2 LAST CDS_LOCATION R3171
J 0
(1925 4175);
DISPLAY 1.021277 (1925 4175);
DISPLAY INVISIBLE (1925 4175);
FORCEPROP 2 LAST $SEC 1
J 0
(1925 4175);
DISPLAY 0.680851 (1925 4175);
PAINT MONO (1925 4175);
DISPLAY INVISIBLE (1925 4175);
FORCEPROP 2 LAST CDS_SEC 1
J 0
(1925 4175);
DISPLAY 1.021277 (1925 4175);
DISPLAY INVISIBLE (1925 4175);
FORCEADD TAP..1
R 2
(3125 1225);
FORCEPROP 3 LASTPIN (3175 1225) SIG_NAME P5E_CPU1_PE1_TX_C_DP<13>
J 0
(3185 1235);
DISPLAY 0.659574 (3185 1235);
PAINT MONO (3185 1235);
DISPLAY INVISIBLE (3185 1235);
FORCEPROP 1 LASTPIN (3175 1225) BN 13
J 2
(3187 1233);
DISPLAY 0.680851 (3187 1233);
PAINT GREEN (3187 1233);
FORCEPROP 2 LAST CDS_LIB standard
J 0
(3125 1225);
PAINT MONO (3125 1225);
DISPLAY INVISIBLE (3125 1225);
FORCEPROP 1 LAST BODY_TYPE PLUMBING
J 2
(3125 1275);
DISPLAY 0.872340 (3125 1275);
PAINT GREEN (3125 1275);
DISPLAY INVISIBLE (3125 1275);
FORCEPROP 1 LAST HDL_TAP TRUE
J 2
(2800 1100);
DISPLAY 0.872340 (2800 1100);
PAINT GREEN (2800 1100);
DISPLAY INVISIBLE (2800 1100);
FORCEPROP 1 LAST PATH I310
J 2
(3127 1225);
DISPLAY 0.872340 (3127 1225);
PAINT GREEN (3127 1225);
DISPLAY INVISIBLE (3127 1225);
FORCEADD TAP..1
R 2
(3275 1575);
FORCEPROP 3 LASTPIN (3325 1575) SIG_NAME P5E_CPU1_PE1_TX_C_DN<11>
J 0
(3335 1585);
DISPLAY 0.659574 (3335 1585);
PAINT MONO (3335 1585);
DISPLAY INVISIBLE (3335 1585);
FORCEPROP 1 LASTPIN (3325 1575) BN 11
J 2
(3337 1583);
DISPLAY 0.680851 (3337 1583);
PAINT GREEN (3337 1583);
FORCEPROP 2 LAST CDS_LIB standard
J 0
(3275 1575);
PAINT MONO (3275 1575);
DISPLAY INVISIBLE (3275 1575);
FORCEPROP 1 LAST BODY_TYPE PLUMBING
J 2
(3275 1625);
DISPLAY 0.872340 (3275 1625);
PAINT GREEN (3275 1625);
DISPLAY INVISIBLE (3275 1625);
FORCEPROP 1 LAST HDL_TAP TRUE
J 2
(2950 1450);
DISPLAY 0.872340 (2950 1450);
PAINT GREEN (2950 1450);
DISPLAY INVISIBLE (2950 1450);
FORCEPROP 1 LAST PATH I312
J 2
(3277 1575);
DISPLAY 0.872340 (3277 1575);
PAINT GREEN (3277 1575);
DISPLAY INVISIBLE (3277 1575);
FORCEADD TAP..1
R 2
(3125 1525);
FORCEPROP 3 LASTPIN (3175 1525) SIG_NAME P5E_CPU1_PE1_TX_C_DP<11>
J 0
(3185 1535);
DISPLAY 0.659574 (3185 1535);
PAINT MONO (3185 1535);
DISPLAY INVISIBLE (3185 1535);
FORCEPROP 1 LASTPIN (3175 1525) BN 11
J 2
(3187 1533);
DISPLAY 0.680851 (3187 1533);
PAINT GREEN (3187 1533);
FORCEPROP 2 LAST CDS_LIB standard
J 0
(3125 1525);
PAINT MONO (3125 1525);
DISPLAY INVISIBLE (3125 1525);
FORCEPROP 1 LAST BODY_TYPE PLUMBING
J 2
(3125 1575);
DISPLAY 0.872340 (3125 1575);
PAINT GREEN (3125 1575);
DISPLAY INVISIBLE (3125 1575);
FORCEPROP 1 LAST HDL_TAP TRUE
J 2
(2800 1400);
DISPLAY 0.872340 (2800 1400);
PAINT GREEN (2800 1400);
DISPLAY INVISIBLE (2800 1400);
FORCEPROP 1 LAST PATH I313
J 2
(3127 1525);
DISPLAY 0.872340 (3127 1525);
PAINT GREEN (3127 1525);
DISPLAY INVISIBLE (3127 1525);
FORCEADD TAP..1
R 2
(3125 1825);
FORCEPROP 3 LASTPIN (3175 1825) SIG_NAME P5E_CPU1_PE1_TX_C_DP<9>
J 0
(3185 1835);
DISPLAY 0.659574 (3185 1835);
PAINT MONO (3185 1835);
DISPLAY INVISIBLE (3185 1835);
FORCEPROP 1 LASTPIN (3175 1825) BN 9
J 2
(3187 1833);
DISPLAY 0.680851 (3187 1833);
PAINT GREEN (3187 1833);
FORCEPROP 2 LAST CDS_LIB standard
J 0
(3125 1825);
PAINT MONO (3125 1825);
DISPLAY INVISIBLE (3125 1825);
FORCEPROP 1 LAST BODY_TYPE PLUMBING
J 2
(3125 1875);
DISPLAY 0.872340 (3125 1875);
PAINT GREEN (3125 1875);
DISPLAY INVISIBLE (3125 1875);
FORCEPROP 1 LAST HDL_TAP TRUE
J 2
(2800 1700);
DISPLAY 0.872340 (2800 1700);
PAINT GREEN (2800 1700);
DISPLAY INVISIBLE (2800 1700);
FORCEPROP 1 LAST PATH I315
J 2
(3127 1825);
DISPLAY 0.872340 (3127 1825);
PAINT GREEN (3127 1825);
DISPLAY INVISIBLE (3127 1825);
FORCEADD TAP..1
R 2
(3275 1875);
FORCEPROP 3 LASTPIN (3325 1875) SIG_NAME P5E_CPU1_PE1_TX_C_DN<9>
J 0
(3335 1885);
DISPLAY 0.659574 (3335 1885);
PAINT MONO (3335 1885);
DISPLAY INVISIBLE (3335 1885);
FORCEPROP 1 LASTPIN (3325 1875) BN 9
J 2
(3337 1883);
DISPLAY 0.680851 (3337 1883);
PAINT GREEN (3337 1883);
FORCEPROP 2 LAST CDS_LIB standard
J 0
(3275 1875);
PAINT MONO (3275 1875);
DISPLAY INVISIBLE (3275 1875);
FORCEPROP 1 LAST BODY_TYPE PLUMBING
J 2
(3275 1925);
DISPLAY 0.872340 (3275 1925);
PAINT GREEN (3275 1925);
DISPLAY INVISIBLE (3275 1925);
FORCEPROP 1 LAST HDL_TAP TRUE
J 2
(2950 1750);
DISPLAY 0.872340 (2950 1750);
PAINT GREEN (2950 1750);
DISPLAY INVISIBLE (2950 1750);
FORCEPROP 1 LAST PATH I316
J 2
(3277 1875);
DISPLAY 0.872340 (3277 1875);
PAINT GREEN (3277 1875);
DISPLAY INVISIBLE (3277 1875);
FORCEADD TAP..1
R 2
(3275 2375);
FORCEPROP 3 LASTPIN (3325 2375) SIG_NAME P5E_CPU1_PE1_TX_C_DN<7>
J 0
(3335 2385);
DISPLAY 0.659574 (3335 2385);
PAINT MONO (3335 2385);
DISPLAY INVISIBLE (3335 2385);
FORCEPROP 1 LASTPIN (3325 2375) BN 7
J 2
(3337 2383);
DISPLAY 0.680851 (3337 2383);
PAINT GREEN (3337 2383);
FORCEPROP 2 LAST CDS_LIB standard
J 0
(3275 2375);
PAINT MONO (3275 2375);
DISPLAY INVISIBLE (3275 2375);
FORCEPROP 1 LAST BODY_TYPE PLUMBING
J 2
(3275 2425);
DISPLAY 0.872340 (3275 2425);
PAINT GREEN (3275 2425);
DISPLAY INVISIBLE (3275 2425);
FORCEPROP 1 LAST HDL_TAP TRUE
J 2
(2950 2250);
DISPLAY 0.872340 (2950 2250);
PAINT GREEN (2950 2250);
DISPLAY INVISIBLE (2950 2250);
FORCEPROP 1 LAST PATH I318
J 2
(3277 2375);
DISPLAY 0.872340 (3277 2375);
PAINT GREEN (3277 2375);
DISPLAY INVISIBLE (3277 2375);
FORCEADD TAP..1
R 2
(3125 2325);
FORCEPROP 3 LASTPIN (3175 2325) SIG_NAME P5E_CPU1_PE1_TX_C_DP<7>
J 0
(3185 2335);
DISPLAY 0.659574 (3185 2335);
PAINT MONO (3185 2335);
DISPLAY INVISIBLE (3185 2335);
FORCEPROP 1 LASTPIN (3175 2325) BN 7
J 2
(3187 2333);
DISPLAY 0.680851 (3187 2333);
PAINT GREEN (3187 2333);
FORCEPROP 2 LAST CDS_LIB standard
J 0
(3125 2325);
PAINT MONO (3125 2325);
DISPLAY INVISIBLE (3125 2325);
FORCEPROP 1 LAST BODY_TYPE PLUMBING
J 2
(3125 2375);
DISPLAY 0.872340 (3125 2375);
PAINT GREEN (3125 2375);
DISPLAY INVISIBLE (3125 2375);
FORCEPROP 1 LAST HDL_TAP TRUE
J 2
(2800 2200);
DISPLAY 0.872340 (2800 2200);
PAINT GREEN (2800 2200);
DISPLAY INVISIBLE (2800 2200);
FORCEPROP 1 LAST PATH I319
J 2
(3127 2325);
DISPLAY 0.872340 (3127 2325);
PAINT GREEN (3127 2325);
DISPLAY INVISIBLE (3127 2325);
FORCEADD Q_RES..1
(1975 4025);
FORCEPROP 1 LAST PART_NUMBER CS00002JB13
J 0
(1850 4100);
DISPLAY 0.638298 (1850 4100);
DISPLAY INVISIBLE (1850 4100);
FORCEPROP 1 LAST PACK_TYPE 0402LF
J 0
(2250 4025);
DISPLAY 0.638298 (2250 4025);
FORCEPROP 1 LAST TOLERANCE 5%
J 0
(2175 4025);
DISPLAY 0.638298 (2175 4025);
FORCEPROP 1 LAST VALUE 0
J 2
(2150 4025);
DISPLAY 0.638298 (2150 4025);
FORCEPROP 1 LAST $LOCATION R3170
J 0
(1750 4025);
DISPLAY 0.787234 (1750 4025);
FORCEPROP 1 LASTPIN (1875 4025) $PN 1
J 0
(1887 4037);
DISPLAY 0.787234 (1887 4037);
FORCEPROP 1 LASTPIN (2075 4025) $PN 2
J 0
(2037 4037);
DISPLAY 0.787234 (2037 4037);
FORCEPROP 1 LAST WATTAGE 1/16W
J 2
(2150 4150);
DISPLAY 0.638298 (2150 4150);
DISPLAY INVISIBLE (2150 4150);
FORCEPROP 1 LAST MATERIAL CHIP
J 0
(1850 4150);
DISPLAY 0.638298 (1850 4150);
DISPLAY INVISIBLE (1850 4150);
FORCEPROP 2 LAST CDS_LIB pure_quanta
J 0
(1975 4025);
PAINT MONO (1975 4025);
DISPLAY INVISIBLE (1975 4025);
FORCEPROP 1 LAST PATH I32
J 0
(1925 4175);
DISPLAY 0.978723 (1925 4175);
PAINT WHITE (1925 4175);
DISPLAY INVISIBLE (1925 4175);
FORCEPROP 2 LAST CDS_LOCATION R3170
J 0
(1925 4225);
DISPLAY 1.021277 (1925 4225);
DISPLAY INVISIBLE (1925 4225);
FORCEPROP 2 LAST $SEC 1
J 0
(1925 4225);
DISPLAY 0.680851 (1925 4225);
PAINT MONO (1925 4225);
DISPLAY INVISIBLE (1925 4225);
FORCEPROP 2 LAST CDS_SEC 1
J 0
(1925 4225);
DISPLAY 1.021277 (1925 4225);
DISPLAY INVISIBLE (1925 4225);
FORCEADD TAP..1
R 2
(3275 2675);
FORCEPROP 3 LASTPIN (3325 2675) SIG_NAME P5E_CPU1_PE1_TX_C_DN<5>
J 0
(3335 2685);
DISPLAY 0.659574 (3335 2685);
PAINT MONO (3335 2685);
DISPLAY INVISIBLE (3335 2685);
FORCEPROP 1 LASTPIN (3325 2675) BN 5
J 2
(3337 2683);
DISPLAY 0.680851 (3337 2683);
PAINT GREEN (3337 2683);
FORCEPROP 2 LAST CDS_LIB standard
J 0
(3275 2675);
PAINT MONO (3275 2675);
DISPLAY INVISIBLE (3275 2675);
FORCEPROP 1 LAST BODY_TYPE PLUMBING
J 2
(3275 2725);
DISPLAY 0.872340 (3275 2725);
PAINT GREEN (3275 2725);
DISPLAY INVISIBLE (3275 2725);
FORCEPROP 1 LAST HDL_TAP TRUE
J 2
(2950 2550);
DISPLAY 0.872340 (2950 2550);
PAINT GREEN (2950 2550);
DISPLAY INVISIBLE (2950 2550);
FORCEPROP 1 LAST PATH I321
J 2
(3277 2675);
DISPLAY 0.872340 (3277 2675);
PAINT GREEN (3277 2675);
DISPLAY INVISIBLE (3277 2675);
FORCEADD TAP..1
R 2
(3125 2625);
FORCEPROP 3 LASTPIN (3175 2625) SIG_NAME P5E_CPU1_PE1_TX_C_DP<5>
J 0
(3185 2635);
DISPLAY 0.659574 (3185 2635);
PAINT MONO (3185 2635);
DISPLAY INVISIBLE (3185 2635);
FORCEPROP 1 LASTPIN (3175 2625) BN 5
J 2
(3187 2633);
DISPLAY 0.680851 (3187 2633);
PAINT GREEN (3187 2633);
FORCEPROP 2 LAST CDS_LIB standard
J 0
(3125 2625);
PAINT MONO (3125 2625);
DISPLAY INVISIBLE (3125 2625);
FORCEPROP 1 LAST BODY_TYPE PLUMBING
J 2
(3125 2675);
DISPLAY 0.872340 (3125 2675);
PAINT GREEN (3125 2675);
DISPLAY INVISIBLE (3125 2675);
FORCEPROP 1 LAST HDL_TAP TRUE
J 2
(2800 2500);
DISPLAY 0.872340 (2800 2500);
PAINT GREEN (2800 2500);
DISPLAY INVISIBLE (2800 2500);
FORCEPROP 1 LAST PATH I322
J 2
(3127 2625);
DISPLAY 0.872340 (3127 2625);
PAINT GREEN (3127 2625);
DISPLAY INVISIBLE (3127 2625);
FORCEADD TAP..1
R 2
(3275 3125);
FORCEPROP 3 LASTPIN (3325 3125) SIG_NAME P5E_CPU1_PE1_TX_C_DN<3>
J 0
(3335 3135);
DISPLAY 0.659574 (3335 3135);
PAINT MONO (3335 3135);
DISPLAY INVISIBLE (3335 3135);
FORCEPROP 1 LASTPIN (3325 3125) BN 3
J 2
(3337 3133);
DISPLAY 0.680851 (3337 3133);
PAINT GREEN (3337 3133);
FORCEPROP 2 LAST CDS_LIB standard
J 0
(3275 3125);
PAINT MONO (3275 3125);
DISPLAY INVISIBLE (3275 3125);
FORCEPROP 1 LAST BODY_TYPE PLUMBING
J 2
(3275 3175);
DISPLAY 0.872340 (3275 3175);
PAINT GREEN (3275 3175);
DISPLAY INVISIBLE (3275 3175);
FORCEPROP 1 LAST HDL_TAP TRUE
J 2
(2950 3000);
DISPLAY 0.872340 (2950 3000);
PAINT GREEN (2950 3000);
DISPLAY INVISIBLE (2950 3000);
FORCEPROP 1 LAST PATH I324
J 2
(3277 3125);
DISPLAY 0.872340 (3277 3125);
PAINT GREEN (3277 3125);
DISPLAY INVISIBLE (3277 3125);
FORCEADD TAP..1
R 2
(3125 3075);
FORCEPROP 3 LASTPIN (3175 3075) SIG_NAME P5E_CPU1_PE1_TX_C_DP<3>
J 0
(3185 3085);
DISPLAY 0.659574 (3185 3085);
PAINT MONO (3185 3085);
DISPLAY INVISIBLE (3185 3085);
FORCEPROP 1 LASTPIN (3175 3075) BN 3
J 2
(3187 3083);
DISPLAY 0.680851 (3187 3083);
PAINT GREEN (3187 3083);
FORCEPROP 2 LAST CDS_LIB standard
J 0
(3125 3075);
PAINT MONO (3125 3075);
DISPLAY INVISIBLE (3125 3075);
FORCEPROP 1 LAST BODY_TYPE PLUMBING
J 2
(3125 3125);
DISPLAY 0.872340 (3125 3125);
PAINT GREEN (3125 3125);
DISPLAY INVISIBLE (3125 3125);
FORCEPROP 1 LAST HDL_TAP TRUE
J 2
(2800 2950);
DISPLAY 0.872340 (2800 2950);
PAINT GREEN (2800 2950);
DISPLAY INVISIBLE (2800 2950);
FORCEPROP 1 LAST PATH I325
J 2
(3127 3075);
DISPLAY 0.872340 (3127 3075);
PAINT GREEN (3127 3075);
DISPLAY INVISIBLE (3127 3075);
FORCEADD TAP..1
R 2
(3275 3425);
FORCEPROP 3 LASTPIN (3325 3425) SIG_NAME P5E_CPU1_PE1_TX_C_DN<1>
J 0
(3335 3435);
DISPLAY 0.659574 (3335 3435);
PAINT MONO (3335 3435);
DISPLAY INVISIBLE (3335 3435);
FORCEPROP 1 LASTPIN (3325 3425) BN 1
J 2
(3337 3433);
DISPLAY 0.680851 (3337 3433);
PAINT GREEN (3337 3433);
FORCEPROP 2 LAST CDS_LIB standard
J 0
(3275 3425);
PAINT MONO (3275 3425);
DISPLAY INVISIBLE (3275 3425);
FORCEPROP 1 LAST BODY_TYPE PLUMBING
J 2
(3275 3475);
DISPLAY 0.872340 (3275 3475);
PAINT GREEN (3275 3475);
DISPLAY INVISIBLE (3275 3475);
FORCEPROP 1 LAST HDL_TAP TRUE
J 2
(2950 3300);
DISPLAY 0.872340 (2950 3300);
PAINT GREEN (2950 3300);
DISPLAY INVISIBLE (2950 3300);
FORCEPROP 1 LAST PATH I327
J 2
(3277 3425);
DISPLAY 0.872340 (3277 3425);
PAINT GREEN (3277 3425);
DISPLAY INVISIBLE (3277 3425);
FORCEADD TAP..1
R 2
(3125 3375);
FORCEPROP 3 LASTPIN (3175 3375) SIG_NAME P5E_CPU1_PE1_TX_C_DP<1>
J 0
(3185 3385);
DISPLAY 0.659574 (3185 3385);
PAINT MONO (3185 3385);
DISPLAY INVISIBLE (3185 3385);
FORCEPROP 1 LASTPIN (3175 3375) BN 1
J 2
(3187 3383);
DISPLAY 0.680851 (3187 3383);
PAINT GREEN (3187 3383);
FORCEPROP 2 LAST CDS_LIB standard
J 0
(3125 3375);
PAINT MONO (3125 3375);
DISPLAY INVISIBLE (3125 3375);
FORCEPROP 1 LAST BODY_TYPE PLUMBING
J 2
(3125 3425);
DISPLAY 0.872340 (3125 3425);
PAINT GREEN (3125 3425);
DISPLAY INVISIBLE (3125 3425);
FORCEPROP 1 LAST HDL_TAP TRUE
J 2
(2800 3250);
DISPLAY 0.872340 (2800 3250);
PAINT GREEN (2800 3250);
DISPLAY INVISIBLE (2800 3250);
FORCEPROP 1 LAST PATH I328
J 2
(3127 3375);
DISPLAY 0.872340 (3127 3375);
PAINT GREEN (3127 3375);
DISPLAY INVISIBLE (3127 3375);
FORCEADD Q_RES..1
(1975 4075);
FORCEPROP 1 LAST PART_NUMBER CS00002JB13
J 0
(1850 4150);
DISPLAY 0.638298 (1850 4150);
DISPLAY INVISIBLE (1850 4150);
FORCEPROP 1 LAST VALUE 0
J 2
(2150 4075);
DISPLAY 0.638298 (2150 4075);
FORCEPROP 1 LAST TOLERANCE 5%
J 0
(2175 4075);
DISPLAY 0.638298 (2175 4075);
FORCEPROP 1 LAST PACK_TYPE 0402LF
J 0
(2250 4075);
DISPLAY 0.638298 (2250 4075);
FORCEPROP 1 LAST MATERIAL CHIP
J 0
(1850 4200);
DISPLAY 0.638298 (1850 4200);
FORCEPROP 1 LAST WATTAGE 1/16W
J 2
(2150 4200);
DISPLAY 0.638298 (2150 4200);
FORCEPROP 1 LAST $LOCATION R3169
J 0
(1750 4075);
DISPLAY 0.787234 (1750 4075);
FORCEPROP 1 LASTPIN (1875 4075) $PN 1
J 0
(1887 4087);
DISPLAY 0.787234 (1887 4087);
FORCEPROP 1 LASTPIN (2075 4075) $PN 2
J 0
(2037 4087);
DISPLAY 0.787234 (2037 4087);
FORCEPROP 2 LAST CDS_LIB pure_quanta
J 0
(1975 4075);
PAINT MONO (1975 4075);
DISPLAY INVISIBLE (1975 4075);
FORCEPROP 1 LAST PATH I33
J 0
(1925 4225);
DISPLAY 0.978723 (1925 4225);
PAINT WHITE (1925 4225);
DISPLAY INVISIBLE (1925 4225);
FORCEPROP 2 LAST CDS_LOCATION R3169
J 0
(1925 4275);
DISPLAY 1.021277 (1925 4275);
DISPLAY INVISIBLE (1925 4275);
FORCEPROP 2 LAST $SEC 1
J 0
(1925 4275);
DISPLAY 0.680851 (1925 4275);
PAINT MONO (1925 4275);
DISPLAY INVISIBLE (1925 4275);
FORCEPROP 2 LAST CDS_SEC 1
J 0
(1925 4275);
DISPLAY 1.021277 (1925 4275);
DISPLAY INVISIBLE (1925 4275);
FORCEADD Q_RES..1
(3675 -225);
FORCEPROP 1 LAST PART_NUMBER CS31002FB08
J 0
(3500 -150);
DISPLAY 0.510638 (3500 -150);
DISPLAY INVISIBLE (3500 -150);
FORCEPROP 1 LAST MATERIAL CHIP
J 0
(3950 -225);
DISPLAY 0.510638 (3950 -225);
FORCEPROP 1 LAST VALUE 10K
J 2
(3850 -225);
DISPLAY 0.510638 (3850 -225);
FORCEPROP 1 LAST TOLERANCE 1%
J 0
(3875 -225);
DISPLAY 0.510638 (3875 -225);
FORCEPROP 1 LAST LOCATION R3174
J 0
(3475 -225);
DISPLAY 0.638298 (3475 -225);
FORCEPROP 1 LASTPIN (3575 -225) $PN 1
J 0
(3587 -213);
DISPLAY 0.787234 (3587 -213);
PAINT MONO (3587 -213);
FORCEPROP 1 LASTPIN (3775 -225) $PN 2
J 0
(3737 -213);
DISPLAY 0.787234 (3737 -213);
PAINT MONO (3737 -213);
FORCEPROP 2 LAST CDS_LIB pure_quanta
J 0
(3675 -225);
DISPLAY INVISIBLE (3675 -225);
FORCEPROP 1 LAST PACK_TYPE 0402LF
J 0
(3500 -100);
DISPLAY 0.510638 (3500 -100);
DISPLAY INVISIBLE (3500 -100);
FORCEPROP 1 LAST WATTAGE 1/16W
J 2
(3875 -100);
DISPLAY 0.510638 (3875 -100);
DISPLAY INVISIBLE (3875 -100);
FORCEPROP 1 LAST PATH I333
J 0
(3625 -75);
DISPLAY 0.978723 (3625 -75);
PAINT WHITE (3625 -75);
DISPLAY INVISIBLE (3625 -75);
FORCEPROP 0 LAST $SEC 1
J 0
(3475 -175);
DISPLAY 0.680851 (3475 -175);
PAINT MONO (3475 -175);
DISPLAY INVISIBLE (3475 -175);
FORCEPROP 0 LAST CDS_SEC 1
J 0
(3475 -175);
DISPLAY 1.021277 (3475 -175);
DISPLAY INVISIBLE (3475 -175);
FORCEADD Q_RES..1
(3700 -575);
FORCEPROP 1 LAST PART_NUMBER CS31002FB08
J 0
(3525 -500);
DISPLAY 0.510638 (3525 -500);
DISPLAY INVISIBLE (3525 -500);
FORCEPROP 1 LAST MATERIAL CHIP
J 0
(3975 -575);
DISPLAY 0.510638 (3975 -575);
FORCEPROP 1 LAST VALUE 10K
J 2
(3875 -575);
DISPLAY 0.510638 (3875 -575);
FORCEPROP 1 LAST TOLERANCE 1%
J 0
(3900 -575);
DISPLAY 0.510638 (3900 -575);
FORCEPROP 1 LAST LOCATION R3175
J 0
(3500 -575);
DISPLAY 0.638298 (3500 -575);
FORCEPROP 1 LASTPIN (3600 -575) $PN 1
J 0
(3612 -563);
DISPLAY 0.787234 (3612 -563);
PAINT MONO (3612 -563);
FORCEPROP 1 LASTPIN (3800 -575) $PN 2
J 0
(3762 -563);
DISPLAY 0.787234 (3762 -563);
PAINT MONO (3762 -563);
FORCEPROP 2 LAST CDS_LIB pure_quanta
J 0
(3700 -575);
DISPLAY INVISIBLE (3700 -575);
FORCEPROP 1 LAST PACK_TYPE 0402LF
J 0
(3525 -450);
DISPLAY 0.510638 (3525 -450);
DISPLAY INVISIBLE (3525 -450);
FORCEPROP 1 LAST WATTAGE 1/16W
J 2
(3900 -450);
DISPLAY 0.510638 (3900 -450);
DISPLAY INVISIBLE (3900 -450);
FORCEPROP 1 LAST PATH I334
J 0
(3650 -425);
DISPLAY 0.978723 (3650 -425);
PAINT WHITE (3650 -425);
DISPLAY INVISIBLE (3650 -425);
FORCEPROP 0 LAST $SEC 1
J 0
(3500 -525);
DISPLAY 0.680851 (3500 -525);
PAINT MONO (3500 -525);
DISPLAY INVISIBLE (3500 -525);
FORCEPROP 0 LAST CDS_SEC 1
J 0
(3500 -525);
DISPLAY 1.021277 (3500 -525);
DISPLAY INVISIBLE (3500 -525);
FORCEADD OFFPAGE..5
(2425 -400);
FORCEPROP 2 LAST $XR1 213 
J 0
(2020 -400);
DISPLAY 0.638298 (2020 -400);
PAINT MONO (2020 -400);
FORCEPROP 2 LAST $XR0 159 
J 0
(2140 -400);
DISPLAY 0.638298 (2140 -400);
PAINT MONO (2140 -400);
FORCEPROP 2 LAST CDS_LIB standard
J 0
(2425 -400);
PAINT MONO (2425 -400);
DISPLAY INVISIBLE (2425 -400);
FORCEPROP 1 LAST OFFPAGE TRUE
J 0
(2750 -525);
DISPLAY 0.872340 (2750 -525);
PAINT GREEN (2750 -525);
DISPLAY INVISIBLE (2750 -525);
FORCEPROP 1 LAST COMMENT_BODY TRUE
J 0
(2525 -475);
DISPLAY 0.872340 (2525 -475);
PAINT GREEN (2525 -475);
DISPLAY INVISIBLE (2525 -475);
FORCEPROP 2 LAST PATH I335
J 0
(2150 -350);
DISPLAY 1.021277 (2150 -350);
DISPLAY INVISIBLE (2150 -350);
FORCEADD Q_RES..1
(3700 -400);
FORCEPROP 1 LAST PART_NUMBER CS21002FB06
J 0
(3650 -350);
DISPLAY 0.510638 (3650 -350);
DISPLAY INVISIBLE (3650 -350);
FORCEPROP 1 LAST WATTAGE 1/16W
J 2
(3950 -300);
DISPLAY 0.510638 (3950 -300);
FORCEPROP 1 LAST MATERIAL CHIP
J 0
(4075 -400);
DISPLAY 0.638298 (4075 -400);
FORCEPROP 1 LAST VALUE 1K
J 2
(3900 -400);
DISPLAY 0.638298 (3900 -400);
FORCEPROP 1 LAST TOLERANCE 1%
J 0
(3950 -400);
DISPLAY 0.638298 (3950 -400);
FORCEPROP 1 LAST PACK_TYPE 0402LF
J 0
(3650 -300);
DISPLAY 0.510638 (3650 -300);
FORCEPROP 1 LAST LOCATION R3176
J 0
(3500 -400);
DISPLAY 0.638298 (3500 -400);
FORCEPROP 1 LASTPIN (3600 -400) $PN 1
J 0
(3612 -388);
DISPLAY 0.787234 (3612 -388);
PAINT MONO (3612 -388);
FORCEPROP 1 LASTPIN (3800 -400) $PN 2
J 0
(3762 -388);
DISPLAY 0.787234 (3762 -388);
PAINT MONO (3762 -388);
FORCEPROP 2 LAST CDS_LIB pure_quanta
J 0
(3700 -400);
DISPLAY INVISIBLE (3700 -400);
FORCEPROP 1 LAST PATH I336
J 0
(3650 -250);
DISPLAY 0.978723 (3650 -250);
PAINT WHITE (3650 -250);
DISPLAY INVISIBLE (3650 -250);
FORCEPROP 0 LAST $SEC 1
J 0
(3950 -275);
DISPLAY 0.680851 (3950 -275);
PAINT MONO (3950 -275);
DISPLAY INVISIBLE (3950 -275);
FORCEPROP 0 LAST CDS_SEC 1
J 0
(3950 -275);
DISPLAY 1.021277 (3950 -275);
DISPLAY INVISIBLE (3950 -275);
FORCEADD OFFPAGE..5
(800 5125);
FORCEPROP 2 LAST $XR1 214 
J 0
(425 5125);
DISPLAY 0.638298 (425 5125);
PAINT MONO (425 5125);
FORCEPROP 2 LAST $XR0 159 
J 0
(545 5125);
DISPLAY 0.638298 (545 5125);
PAINT MONO (545 5125);
FORCEPROP 2 LAST CDS_LIB standard
J 0
(800 5125);
DISPLAY INVISIBLE (800 5125);
FORCEPROP 1 LAST OFFPAGE TRUE
J 0
(1125 5000);
DISPLAY 0.872340 (1125 5000);
PAINT GREEN (1125 5000);
DISPLAY INVISIBLE (1125 5000);
FORCEPROP 1 LAST COMMENT_BODY TRUE
J 0
(900 5050);
DISPLAY 0.872340 (900 5050);
PAINT GREEN (900 5050);
DISPLAY INVISIBLE (900 5050);
FORCEPROP 2 LAST PATH I337
J 0
(850 5200);
DISPLAY 1.021277 (850 5200);
DISPLAY INVISIBLE (850 5200);
FORCEADD Q_RES..1
(6400 4025);
FORCEPROP 1 LAST PART_NUMBER CS12002FB06
J 0
(6525 4050);
DISPLAY 0.404255 (6525 4050);
DISPLAY INVISIBLE (6525 4050);
FORCEPROP 1 LAST TOLERANCE 1%
J 0
(6625 4025);
DISPLAY 0.510638 (6625 4025);
FORCEPROP 1 LAST WATTAGE 1/16W
J 2
(6850 4050);
DISPLAY 0.404255 (6850 4050);
FORCEPROP 1 LAST VALUE 200
J 2
(6600 4025);
DISPLAY 0.510638 (6600 4025);
FORCEPROP 1 LAST PACK_TYPE 0402LF
J 0
(6725 4025);
DISPLAY 0.510638 (6725 4025);
FORCEPROP 1 LAST MATERIAL CHIP
J 0
(6875 4050);
DISPLAY 0.404255 (6875 4050);
FORCEPROP 1 LAST LOCATION R3229
J 0
(6200 4025);
DISPLAY 0.638298 (6200 4025);
FORCEPROP 1 LASTPIN (6300 4025) $PN 1
J 0
(6312 4037);
DISPLAY 0.787234 (6312 4037);
FORCEPROP 1 LASTPIN (6500 4025) $PN 2
J 0
(6462 4037);
DISPLAY 0.787234 (6462 4037);
FORCEPROP 1 LAST PATH I338
J 0
(6350 4175);
DISPLAY 0.978723 (6350 4175);
PAINT WHITE (6350 4175);
DISPLAY INVISIBLE (6350 4175);
FORCEPROP 2 LAST CDS_LIB pure_quanta
J 0
(6400 4025);
PAINT MONO (6400 4025);
DISPLAY INVISIBLE (6400 4025);
FORCEPROP 1 LAST LOCATION R3229
J 0
(6350 4225);
DISPLAY 1.021277 (6350 4225);
DISPLAY INVISIBLE (6350 4225);
FORCEPROP 2 LAST $SEC 1
J 0
(6350 4225);
DISPLAY 0.680851 (6350 4225);
PAINT MONO (6350 4225);
DISPLAY INVISIBLE (6350 4225);
FORCEPROP 2 LAST CDS_SEC 1
J 0
(6350 4225);
DISPLAY 1.021277 (6350 4225);
DISPLAY INVISIBLE (6350 4225);
FORCEADD Q_RES..1
(6400 4075);
FORCEPROP 1 LAST PART_NUMBER CS12002FB06
J 0
(6525 4100);
DISPLAY 0.404255 (6525 4100);
DISPLAY INVISIBLE (6525 4100);
FORCEPROP 1 LAST WATTAGE 1/16W
J 2
(6850 4100);
DISPLAY 0.404255 (6850 4100);
FORCEPROP 1 LAST PACK_TYPE 0402LF
J 0
(6725 4075);
DISPLAY 0.510638 (6725 4075);
FORCEPROP 1 LAST VALUE 200
J 2
(6600 4075);
DISPLAY 0.510638 (6600 4075);
FORCEPROP 1 LAST MATERIAL CHIP
J 0
(6875 4100);
DISPLAY 0.404255 (6875 4100);
FORCEPROP 1 LAST TOLERANCE 1%
J 0
(6625 4075);
DISPLAY 0.510638 (6625 4075);
FORCEPROP 1 LAST LOCATION R3228
J 0
(6200 4075);
DISPLAY 0.638298 (6200 4075);
FORCEPROP 1 LASTPIN (6300 4075) $PN 1
J 0
(6312 4087);
DISPLAY 0.787234 (6312 4087);
FORCEPROP 1 LASTPIN (6500 4075) $PN 2
J 0
(6462 4087);
DISPLAY 0.787234 (6462 4087);
FORCEPROP 2 LAST CDS_LIB pure_quanta
J 0
(6400 4075);
PAINT MONO (6400 4075);
DISPLAY INVISIBLE (6400 4075);
FORCEPROP 1 LAST PATH I339
J 0
(6350 4225);
DISPLAY 0.978723 (6350 4225);
PAINT WHITE (6350 4225);
DISPLAY INVISIBLE (6350 4225);
FORCEPROP 1 LAST LOCATION R3228
J 0
(6350 4275);
DISPLAY 1.021277 (6350 4275);
DISPLAY INVISIBLE (6350 4275);
FORCEPROP 2 LAST $SEC 1
J 0
(6350 4275);
DISPLAY 0.680851 (6350 4275);
PAINT MONO (6350 4275);
DISPLAY INVISIBLE (6350 4275);
FORCEPROP 2 LAST CDS_SEC 1
J 0
(6350 4275);
DISPLAY 1.021277 (6350 4275);
DISPLAY INVISIBLE (6350 4275);
FORCEADD OFFPAGE..1
(1025 3925);
FORCEPROP 2 LAST $XR0 161 
J 0
(743 3925);
DISPLAY 0.638298 (743 3925);
PAINT MONO (743 3925);
FORCEPROP 2 LAST CDS_LIB standard
J 0
(1025 3925);
PAINT MONO (1025 3925);
DISPLAY INVISIBLE (1025 3925);
FORCEPROP 1 LAST OFFPAGE TRUE
J 0
(1350 3800);
DISPLAY 0.872340 (1350 3800);
PAINT GREEN (1350 3800);
DISPLAY INVISIBLE (1350 3800);
FORCEPROP 1 LAST COMMENT_BODY TRUE
J 0
(1150 3825);
DISPLAY 0.872340 (1150 3825);
PAINT GREEN (1150 3825);
DISPLAY INVISIBLE (1150 3825);
FORCEPROP 2 LAST PATH I34
J 0
(775 3975);
DISPLAY 1.021277 (775 3975);
DISPLAY INVISIBLE (775 3975);
FORCEADD OFFPAGE..1
(1025 3825);
FORCEPROP 2 LAST $XR3 161 
J 0
(383 3825);
DISPLAY 0.638298 (383 3825);
PAINT MONO (383 3825);
FORCEPROP 2 LAST $XR2 160 
J 0
(503 3825);
DISPLAY 0.638298 (503 3825);
PAINT MONO (503 3825);
FORCEPROP 2 LAST $XR1 164 
J 0
(623 3825);
DISPLAY 0.638298 (623 3825);
PAINT MONO (623 3825);
FORCEPROP 2 LAST $XR0 159 
J 0
(743 3825);
DISPLAY 0.638298 (743 3825);
PAINT MONO (743 3825);
FORCEPROP 2 LAST CDS_LIB standard
J 0
(1025 3825);
PAINT MONO (1025 3825);
DISPLAY INVISIBLE (1025 3825);
FORCEPROP 1 LAST OFFPAGE TRUE
J 0
(1350 3700);
DISPLAY 0.872340 (1350 3700);
PAINT GREEN (1350 3700);
DISPLAY INVISIBLE (1350 3700);
FORCEPROP 1 LAST COMMENT_BODY TRUE
J 0
(1150 3725);
DISPLAY 0.872340 (1150 3725);
PAINT GREEN (1150 3725);
DISPLAY INVISIBLE (1150 3725);
FORCEPROP 2 LAST PATH I35
J 0
(775 3875);
DISPLAY 1.021277 (775 3875);
DISPLAY INVISIBLE (775 3875);
FORCEADD Q_RES..1
(1975 3825);
FORCEPROP 1 LAST PART_NUMBER CS00002JB13
J 0
(1850 3900);
DISPLAY 0.638298 (1850 3900);
DISPLAY INVISIBLE (1850 3900);
FORCEPROP 1 LAST VALUE 0
J 2
(2150 3825);
DISPLAY 0.638298 (2150 3825);
FORCEPROP 1 LAST TOLERANCE 5%
J 0
(2175 3825);
DISPLAY 0.638298 (2175 3825);
FORCEPROP 1 LAST PACK_TYPE 0402LF
J 0
(2250 3825);
DISPLAY 0.638298 (2250 3825);
FORCEPROP 1 LAST $LOCATION R3172
J 0
(1725 3825);
DISPLAY 0.787234 (1725 3825);
FORCEPROP 1 LASTPIN (1875 3825) $PN 1
J 0
(1887 3837);
DISPLAY 0.787234 (1887 3837);
FORCEPROP 1 LASTPIN (2075 3825) $PN 2
J 0
(2037 3837);
DISPLAY 0.787234 (2037 3837);
FORCEPROP 1 LAST WATTAGE 1/16W
J 2
(2150 3950);
DISPLAY 0.638298 (2150 3950);
DISPLAY INVISIBLE (2150 3950);
FORCEPROP 1 LAST MATERIAL CHIP
J 0
(1850 3950);
DISPLAY 0.638298 (1850 3950);
DISPLAY INVISIBLE (1850 3950);
FORCEPROP 2 LAST CDS_LIB pure_quanta
J 0
(1975 3825);
PAINT MONO (1975 3825);
DISPLAY INVISIBLE (1975 3825);
FORCEPROP 1 LAST PATH I36
J 0
(1925 3975);
DISPLAY 0.978723 (1925 3975);
PAINT WHITE (1925 3975);
DISPLAY INVISIBLE (1925 3975);
FORCEPROP 2 LAST CDS_LOCATION R3172
J 0
(1925 4025);
DISPLAY 1.021277 (1925 4025);
DISPLAY INVISIBLE (1925 4025);
FORCEPROP 2 LAST $SEC 1
J 0
(1925 4025);
DISPLAY 0.680851 (1925 4025);
PAINT MONO (1925 4025);
DISPLAY INVISIBLE (1925 4025);
FORCEPROP 2 LAST CDS_SEC 1
J 0
(1925 4025);
DISPLAY 1.021277 (1925 4025);
DISPLAY INVISIBLE (1925 4025);
FORCEADD Q_RES..1
(750 2800);
FORCEPROP 1 LAST PART_NUMBER CS31002FB08
J 0
(575 2875);
DISPLAY 0.510638 (575 2875);
DISPLAY INVISIBLE (575 2875);
FORCEPROP 1 LAST VALUE 10K
J 2
(925 2800);
DISPLAY 0.510638 (925 2800);
FORCEPROP 1 LAST MATERIAL CHIP
J 0
(1025 2800);
DISPLAY 0.510638 (1025 2800);
FORCEPROP 1 LAST TOLERANCE 1%
J 0
(950 2800);
DISPLAY 0.510638 (950 2800);
FORCEPROP 1 LAST $LOCATION R3165
J 0
(475 2800);
DISPLAY 0.787234 (475 2800);
FORCEPROP 1 LASTPIN (650 2800) $PN 1
J 0
(662 2812);
DISPLAY 0.787234 (662 2812);
PAINT MONO (662 2812);
FORCEPROP 1 LASTPIN (850 2800) $PN 2
J 0
(812 2812);
DISPLAY 0.787234 (812 2812);
PAINT MONO (812 2812);
FORCEPROP 1 LAST WATTAGE 1/16W
J 2
(950 2925);
DISPLAY 0.510638 (950 2925);
DISPLAY INVISIBLE (950 2925);
FORCEPROP 1 LAST PACK_TYPE 0402LF
J 0
(575 2925);
DISPLAY 0.510638 (575 2925);
DISPLAY INVISIBLE (575 2925);
FORCEPROP 2 LAST CDS_LIB pure_quanta
J 0
(750 2800);
DISPLAY INVISIBLE (750 2800);
FORCEPROP 1 LAST PATH I37
J 0
(700 2950);
DISPLAY 0.978723 (700 2950);
PAINT WHITE (700 2950);
DISPLAY INVISIBLE (700 2950);
FORCEPROP 0 LAST CDS_LOCATION R3165
J 0
(475 2850);
DISPLAY 1.021277 (475 2850);
DISPLAY INVISIBLE (475 2850);
FORCEPROP 0 LAST $SEC 1
J 0
(475 2850);
DISPLAY 0.680851 (475 2850);
PAINT MONO (475 2850);
DISPLAY INVISIBLE (475 2850);
FORCEPROP 0 LAST CDS_SEC 1
J 0
(475 2850);
DISPLAY 1.021277 (475 2850);
DISPLAY INVISIBLE (475 2850);
FORCEADD Q_RES..1
(750 2900);
FORCEPROP 1 LAST PART_NUMBER CS31002FB08
J 0
(575 2975);
DISPLAY 0.510638 (575 2975);
DISPLAY INVISIBLE (575 2975);
FORCEPROP 1 LAST VALUE 10K
J 2
(925 2900);
DISPLAY 0.510638 (925 2900);
FORCEPROP 1 LAST TOLERANCE 1%
J 0
(950 2900);
DISPLAY 0.510638 (950 2900);
FORCEPROP 1 LAST WATTAGE 1/16W
J 2
(950 3025);
DISPLAY 0.510638 (950 3025);
FORCEPROP 1 LAST PACK_TYPE 0402LF
J 0
(575 3025);
DISPLAY 0.510638 (575 3025);
FORCEPROP 1 LAST MATERIAL CHIP
J 0
(1025 2900);
DISPLAY 0.510638 (1025 2900);
FORCEPROP 1 LAST $LOCATION R3164
J 0
(475 2900);
DISPLAY 0.787234 (475 2900);
FORCEPROP 1 LASTPIN (650 2900) $PN 1
J 0
(662 2912);
DISPLAY 0.787234 (662 2912);
PAINT MONO (662 2912);
FORCEPROP 1 LASTPIN (850 2900) $PN 2
J 0
(812 2912);
DISPLAY 0.787234 (812 2912);
PAINT MONO (812 2912);
FORCEPROP 2 LAST CDS_LIB pure_quanta
J 0
(750 2900);
DISPLAY INVISIBLE (750 2900);
FORCEPROP 1 LAST PATH I38
J 0
(700 3050);
DISPLAY 0.978723 (700 3050);
PAINT WHITE (700 3050);
DISPLAY INVISIBLE (700 3050);
FORCEPROP 0 LAST CDS_LOCATION R3164
J 0
(950 3050);
DISPLAY 1.021277 (950 3050);
DISPLAY INVISIBLE (950 3050);
FORCEPROP 0 LAST $SEC 1
J 0
(950 3050);
DISPLAY 0.680851 (950 3050);
PAINT MONO (950 3050);
DISPLAY INVISIBLE (950 3050);
FORCEPROP 0 LAST CDS_SEC 1
J 0
(950 3050);
DISPLAY 1.021277 (950 3050);
DISPLAY INVISIBLE (950 3050);
FORCEADD OFFPAGE..2
(2150 2600);
FORCEPROP 2 LAST $XR2 213 
J 0
(2579 2600);
DISPLAY 0.638298 (2579 2600);
PAINT MONO (2579 2600);
FORCEPROP 2 LAST $XR1 160 
J 0
(2459 2600);
DISPLAY 0.638298 (2459 2600);
PAINT MONO (2459 2600);
FORCEPROP 2 LAST $XR0 159 
J 0
(2339 2600);
DISPLAY 0.638298 (2339 2600);
PAINT MONO (2339 2600);
FORCEPROP 2 LAST CDS_LIB standard
J 0
(2150 2600);
DISPLAY INVISIBLE (2150 2600);
FORCEPROP 1 LAST OFFPAGE TRUE
J 0
(2475 2475);
DISPLAY 0.872340 (2475 2475);
PAINT GREEN (2475 2475);
DISPLAY INVISIBLE (2475 2475);
FORCEPROP 1 LAST COMMENT_BODY TRUE
J 0
(2105 2505);
DISPLAY 0.872340 (2105 2505);
PAINT GREEN (2105 2505);
DISPLAY INVISIBLE (2105 2505);
FORCEPROP 2 LAST PATH I39
J 0
(2600 2650);
DISPLAY 1.021277 (2600 2650);
DISPLAY INVISIBLE (2600 2650);
FORCEADD OFFPAGE..2
(2100 2900);
FORCEPROP 2 LAST $XR3 161 
J 0
(2649 2900);
DISPLAY 0.638298 (2649 2900);
PAINT MONO (2649 2900);
FORCEPROP 2 LAST $XR2 160 
J 0
(2529 2900);
DISPLAY 0.638298 (2529 2900);
PAINT MONO (2529 2900);
FORCEPROP 2 LAST $XR1 159 
J 0
(2409 2900);
DISPLAY 0.638298 (2409 2900);
PAINT MONO (2409 2900);
FORCEPROP 2 LAST $XR0 164 
J 0
(2289 2900);
DISPLAY 0.638298 (2289 2900);
PAINT MONO (2289 2900);
FORCEPROP 2 LAST CDS_LIB standard
J 0
(2100 2900);
DISPLAY INVISIBLE (2100 2900);
FORCEPROP 1 LAST OFFPAGE TRUE
J 0
(2425 2775);
DISPLAY 0.872340 (2425 2775);
PAINT GREEN (2425 2775);
DISPLAY INVISIBLE (2425 2775);
FORCEPROP 1 LAST COMMENT_BODY TRUE
J 0
(2055 2805);
DISPLAY 0.872340 (2055 2805);
PAINT GREEN (2055 2805);
DISPLAY INVISIBLE (2055 2805);
FORCEPROP 2 LAST PATH I40
J 0
(2550 2950);
DISPLAY 1.021277 (2550 2950);
DISPLAY INVISIBLE (2550 2950);
FORCEADD OFFPAGE..2
(2100 2800);
FORCEPROP 2 LAST $XR1 214 
J 0
(2409 2800);
DISPLAY 0.638298 (2409 2800);
PAINT MONO (2409 2800);
FORCEPROP 2 LAST $XR0 159 
J 0
(2289 2800);
DISPLAY 0.638298 (2289 2800);
PAINT MONO (2289 2800);
FORCEPROP 2 LAST CDS_LIB standard
J 0
(2100 2800);
DISPLAY INVISIBLE (2100 2800);
FORCEPROP 1 LAST OFFPAGE TRUE
J 0
(2425 2675);
DISPLAY 0.872340 (2425 2675);
PAINT GREEN (2425 2675);
DISPLAY INVISIBLE (2425 2675);
FORCEPROP 1 LAST COMMENT_BODY TRUE
J 0
(2055 2705);
DISPLAY 0.872340 (2055 2705);
PAINT GREEN (2055 2705);
DISPLAY INVISIBLE (2055 2705);
FORCEPROP 2 LAST PATH I41
J 0
(2300 2850);
DISPLAY 1.021277 (2300 2850);
DISPLAY INVISIBLE (2300 2850);
FORCEADD UNIVERSAL_GND..1
(325 2450);
FORCEPROP 3 LASTPIN (325 2500) SIG_NAME GND\g
J 0
(335 2510);
DISPLAY 0.659574 (335 2510);
PAINT MONO (335 2510);
DISPLAY INVISIBLE (335 2510);
FORCEPROP 2 LAST CDS_LIB logical_power
J 0
(325 2450);
DISPLAY INVISIBLE (325 2450);
FORCEPROP 1 LAST HDL_POWER GND
J 1
(350 2375);
DISPLAY 0.872340 (350 2375);
PAINT GREEN (350 2375);
DISPLAY INVISIBLE (350 2375);
FORCEPROP 1 LAST PATH I42
J 0
(400 2450);
DISPLAY 0.872340 (400 2450);
PAINT AQUA (400 2450);
DISPLAY INVISIBLE (400 2450);
FORCEADD Q_RES..1
(800 2600);
FORCEPROP 1 LAST PART_NUMBER CS41002FB09
J 0
(625 2650);
DISPLAY 0.510638 (625 2650);
DISPLAY INVISIBLE (625 2650);
FORCEPROP 1 LAST PACK_TYPE 0402LF
J 0
(625 2700);
DISPLAY 0.510638 (625 2700);
FORCEPROP 1 LAST MATERIAL CHIP
J 0
(1125 2600);
DISPLAY 0.510638 (1125 2600);
FORCEPROP 1 LAST TOLERANCE 1%
J 0
(1025 2600);
DISPLAY 0.510638 (1025 2600);
FORCEPROP 1 LAST WATTAGE 1/16W
J 2
(1000 2700);
DISPLAY 0.510638 (1000 2700);
FORCEPROP 1 LAST VALUE 100K
J 2
(1000 2600);
DISPLAY 0.510638 (1000 2600);
FORCEPROP 1 LAST LOCATION R413
J 0
(525 2600);
DISPLAY 0.787234 (525 2600);
FORCEPROP 1 LASTPIN (700 2600) $PN 1
J 0
(712 2612);
DISPLAY 0.787234 (712 2612);
PAINT MONO (712 2612);
FORCEPROP 1 LASTPIN (900 2600) $PN 2
J 0
(862 2612);
DISPLAY 0.787234 (862 2612);
PAINT MONO (862 2612);
FORCEPROP 2 LAST CDS_LIB pure_quanta
J 0
(800 2600);
DISPLAY INVISIBLE (800 2600);
FORCEPROP 1 LAST PATH I43
J 0
(750 2750);
DISPLAY 0.978723 (750 2750);
PAINT WHITE (750 2750);
DISPLAY INVISIBLE (750 2750);
FORCEPROP 0 LAST $SEC 1
J 0
(1000 2725);
DISPLAY 0.680851 (1000 2725);
PAINT MONO (1000 2725);
DISPLAY INVISIBLE (1000 2725);
FORCEPROP 0 LAST CDS_SEC 1
J 0
(1000 2725);
DISPLAY 1.021277 (1000 2725);
DISPLAY INVISIBLE (1000 2725);
FORCEADD OFFPAGE..1
(2400 3725);
FORCEPROP 2 LAST $XR0 207 
J 0
(2148 3725);
DISPLAY 0.638298 (2148 3725);
PAINT MONO (2148 3725);
FORCEPROP 2 LAST CDS_LIB standard
J 0
(2400 3725);
PAINT MONO (2400 3725);
DISPLAY INVISIBLE (2400 3725);
FORCEPROP 1 LAST OFFPAGE TRUE
J 0
(2725 3600);
DISPLAY 0.872340 (2725 3600);
PAINT GREEN (2725 3600);
DISPLAY INVISIBLE (2725 3600);
FORCEPROP 1 LAST COMMENT_BODY TRUE
J 0
(2525 3625);
DISPLAY 0.872340 (2525 3625);
PAINT GREEN (2525 3625);
DISPLAY INVISIBLE (2525 3625);
FORCEPROP 2 LAST PATH I44
J 0
(2150 3775);
DISPLAY 1.021277 (2150 3775);
DISPLAY INVISIBLE (2150 3775);
FORCEADD OFFPAGE..1
(2400 3675);
FORCEPROP 2 LAST $XR0 207 
J 0
(2148 3675);
DISPLAY 0.638298 (2148 3675);
PAINT MONO (2148 3675);
FORCEPROP 2 LAST CDS_LIB standard
J 0
(2400 3675);
PAINT MONO (2400 3675);
DISPLAY INVISIBLE (2400 3675);
FORCEPROP 1 LAST OFFPAGE TRUE
J 0
(2725 3550);
DISPLAY 0.872340 (2725 3550);
PAINT GREEN (2725 3550);
DISPLAY INVISIBLE (2725 3550);
FORCEPROP 1 LAST COMMENT_BODY TRUE
J 0
(2525 3575);
DISPLAY 0.872340 (2525 3575);
PAINT GREEN (2525 3575);
DISPLAY INVISIBLE (2525 3575);
FORCEPROP 2 LAST PATH I45
J 0
(2150 3725);
DISPLAY 1.021277 (2150 3725);
DISPLAY INVISIBLE (2150 3725);
FORCEADD OFFPAGE..1
R 2
(6800 3725);
FORCEPROP 2 LAST $XR0 207 
J 0
(6986 3725);
DISPLAY 0.638298 (6986 3725);
PAINT MONO (6986 3725);
FORCEPROP 2 LAST CDS_LIB standard
J 2
(6800 3725);
DISPLAY INVISIBLE (6800 3725);
FORCEPROP 1 LAST OFFPAGE TRUE
J 2
(6475 3600);
DISPLAY 0.872340 (6475 3600);
PAINT GREEN (6475 3600);
DISPLAY INVISIBLE (6475 3600);
FORCEPROP 1 LAST COMMENT_BODY TRUE
J 2
(6675 3625);
DISPLAY 0.872340 (6675 3625);
PAINT GREEN (6675 3625);
DISPLAY INVISIBLE (6675 3625);
FORCEPROP 2 LAST PATH I46
J 2
(6750 3800);
DISPLAY 1.021277 (6750 3800);
DISPLAY INVISIBLE (6750 3800);
FORCEADD OFFPAGE..1
R 2
(6800 3675);
FORCEPROP 2 LAST $XR0 207 
J 0
(6986 3675);
DISPLAY 0.638298 (6986 3675);
PAINT MONO (6986 3675);
FORCEPROP 2 LAST CDS_LIB standard
J 2
(6800 3675);
DISPLAY INVISIBLE (6800 3675);
FORCEPROP 1 LAST OFFPAGE TRUE
J 2
(6475 3550);
DISPLAY 0.872340 (6475 3550);
PAINT GREEN (6475 3550);
DISPLAY INVISIBLE (6475 3550);
FORCEPROP 1 LAST COMMENT_BODY TRUE
J 2
(6675 3575);
DISPLAY 0.872340 (6675 3575);
PAINT GREEN (6675 3575);
DISPLAY INVISIBLE (6675 3575);
FORCEPROP 2 LAST PATH I47
J 2
(6750 3750);
DISPLAY 1.021277 (6750 3750);
DISPLAY INVISIBLE (6750 3750);
FORCEADD OFFPAGE..1
R 2
(6275 4625);
FORCEPROP 2 LAST $XR0 207 
J 0
(6461 4625);
DISPLAY 0.638298 (6461 4625);
PAINT MONO (6461 4625);
FORCEPROP 2 LAST CDS_LIB standard
J 0
(6275 4625);
DISPLAY INVISIBLE (6275 4625);
FORCEPROP 1 LAST OFFPAGE TRUE
J 2
(5950 4500);
DISPLAY 0.872340 (5950 4500);
PAINT GREEN (5950 4500);
DISPLAY INVISIBLE (5950 4500);
FORCEPROP 1 LAST COMMENT_BODY TRUE
J 2
(6150 4525);
DISPLAY 0.872340 (6150 4525);
PAINT GREEN (6150 4525);
DISPLAY INVISIBLE (6150 4525);
FORCEPROP 2 LAST PATH I48
J 0
(6450 4700);
DISPLAY 1.021277 (6450 4700);
DISPLAY INVISIBLE (6450 4700);
FORCEADD OFFPAGE..1
R 2
(6275 4675);
FORCEPROP 2 LAST $XR0 207 
J 0
(6461 4675);
DISPLAY 0.638298 (6461 4675);
PAINT MONO (6461 4675);
FORCEPROP 2 LAST CDS_LIB standard
J 0
(6275 4675);
DISPLAY INVISIBLE (6275 4675);
FORCEPROP 1 LAST OFFPAGE TRUE
J 2
(5950 4550);
DISPLAY 0.872340 (5950 4550);
PAINT GREEN (5950 4550);
DISPLAY INVISIBLE (5950 4550);
FORCEPROP 1 LAST COMMENT_BODY TRUE
J 2
(6150 4575);
DISPLAY 0.872340 (6150 4575);
PAINT GREEN (6150 4575);
DISPLAY INVISIBLE (6150 4575);
FORCEPROP 2 LAST PATH I49
J 0
(6450 4750);
DISPLAY 1.021277 (6450 4750);
DISPLAY INVISIBLE (6450 4750);
FORCEADD Q_RES..1
(1975 5125);
FORCEPROP 1 LAST PART_NUMBER CS00002JB13
J 0
(1850 5200);
DISPLAY 0.638298 (1850 5200);
DISPLAY INVISIBLE (1850 5200);
FORCEPROP 1 LAST TOLERANCE 5%
J 0
(2175 5125);
DISPLAY 0.638298 (2175 5125);
FORCEPROP 1 LAST VALUE 0
J 2
(2150 5125);
DISPLAY 0.638298 (2150 5125);
FORCEPROP 1 LAST PACK_TYPE 0402LF
J 0
(2250 5125);
DISPLAY 0.638298 (2250 5125);
FORCEPROP 1 LAST $LOCATION R3168
J 0
(1750 5125);
DISPLAY 0.638298 (1750 5125);
FORCEPROP 1 LASTPIN (1875 5125) $PN 1
J 0
(1887 5137);
DISPLAY 0.787234 (1887 5137);
FORCEPROP 1 LASTPIN (2075 5125) $PN 2
J 0
(2037 5137);
DISPLAY 0.787234 (2037 5137);
FORCEPROP 1 LAST MATERIAL CHIP
J 0
(1850 5250);
DISPLAY 0.638298 (1850 5250);
DISPLAY INVISIBLE (1850 5250);
FORCEPROP 1 LAST WATTAGE 1/16W
J 2
(2150 5250);
DISPLAY 0.638298 (2150 5250);
DISPLAY INVISIBLE (2150 5250);
FORCEPROP 2 LAST CDS_LIB pure_quanta
J 0
(1975 5125);
PAINT MONO (1975 5125);
DISPLAY INVISIBLE (1975 5125);
FORCEPROP 1 LAST PATH I5
J 0
(1925 5275);
DISPLAY 0.978723 (1925 5275);
PAINT WHITE (1925 5275);
DISPLAY INVISIBLE (1925 5275);
FORCEPROP 2 LAST CDS_LOCATION R3168
J 0
(1925 5325);
DISPLAY 1.021277 (1925 5325);
DISPLAY INVISIBLE (1925 5325);
FORCEPROP 2 LAST $SEC 1
J 0
(1925 5325);
DISPLAY 0.680851 (1925 5325);
PAINT MONO (1925 5325);
DISPLAY INVISIBLE (1925 5325);
FORCEPROP 2 LAST CDS_SEC 1
J 0
(1925 5325);
DISPLAY 1.021277 (1925 5325);
DISPLAY INVISIBLE (1925 5325);
FORCEADD UNIVERSAL_POWER..1
(2575 4275);
FORCEPROP 3 LASTPIN (2575 4225) SIG_NAME P3V3_OCP_V3_2\g
J 0
(2585 4235);
DISPLAY 0.659574 (2585 4235);
PAINT MONO (2585 4235);
DISPLAY INVISIBLE (2585 4235);
FORCEPROP 1 LAST HDL_POWER P3V3_OCP_V3_2
J 1
(2575 4325);
DISPLAY 0.872340 (2575 4325);
PAINT GREEN (2575 4325);
FORCEPROP 2 LAST CDS_LIB logical_power
J 0
(2575 4275);
DISPLAY INVISIBLE (2575 4275);
FORCEPROP 1 LAST PATH I51
J 0
(2625 4300);
DISPLAY 0.872340 (2625 4300);
PAINT AQUA (2625 4300);
DISPLAY INVISIBLE (2625 4300);
FORCEADD OFFPAGE..1
(2525 4625);
FORCEPROP 2 LAST $XR0 207 
J 0
(2273 4625);
DISPLAY 0.638298 (2273 4625);
PAINT MONO (2273 4625);
FORCEPROP 2 LAST CDS_LIB standard
J 0
(2525 4625);
PAINT MONO (2525 4625);
DISPLAY INVISIBLE (2525 4625);
FORCEPROP 1 LAST OFFPAGE TRUE
J 0
(2850 4500);
DISPLAY 0.872340 (2850 4500);
PAINT GREEN (2850 4500);
DISPLAY INVISIBLE (2850 4500);
FORCEPROP 1 LAST COMMENT_BODY TRUE
J 0
(2650 4525);
DISPLAY 0.872340 (2650 4525);
PAINT GREEN (2650 4525);
DISPLAY INVISIBLE (2650 4525);
FORCEPROP 2 LAST PATH I6
J 0
(2275 4675);
DISPLAY 1.021277 (2275 4675);
DISPLAY INVISIBLE (2275 4675);
FORCEADD OFFPAGE..1
(2525 4675);
FORCEPROP 2 LAST $XR0 207 
J 0
(2273 4675);
DISPLAY 0.638298 (2273 4675);
PAINT MONO (2273 4675);
FORCEPROP 2 LAST CDS_LIB standard
J 0
(2525 4675);
PAINT MONO (2525 4675);
DISPLAY INVISIBLE (2525 4675);
FORCEPROP 1 LAST OFFPAGE TRUE
J 0
(2850 4550);
DISPLAY 0.872340 (2850 4550);
PAINT GREEN (2850 4550);
DISPLAY INVISIBLE (2850 4550);
FORCEPROP 1 LAST COMMENT_BODY TRUE
J 0
(2650 4575);
DISPLAY 0.872340 (2650 4575);
PAINT GREEN (2650 4575);
DISPLAY INVISIBLE (2650 4575);
FORCEPROP 2 LAST PATH I7
J 0
(2275 4725);
DISPLAY 1.021277 (2275 4725);
DISPLAY INVISIBLE (2275 4725);
FORCEADD OFFPAGE..5
(2525 4525);
FORCEPROP 2 LAST $XR0 160 
J 0
(2270 4525);
DISPLAY 0.638298 (2270 4525);
PAINT MONO (2270 4525);
FORCEPROP 2 LAST CDS_LIB standard
J 0
(2525 4525);
PAINT MONO (2525 4525);
DISPLAY INVISIBLE (2525 4525);
FORCEPROP 1 LAST OFFPAGE TRUE
J 0
(2850 4400);
DISPLAY 0.872340 (2850 4400);
PAINT GREEN (2850 4400);
DISPLAY INVISIBLE (2850 4400);
FORCEPROP 1 LAST COMMENT_BODY TRUE
J 0
(2625 4450);
DISPLAY 0.872340 (2625 4450);
PAINT GREEN (2625 4450);
DISPLAY INVISIBLE (2625 4450);
FORCEPROP 2 LAST PATH I8
J 0
(2250 4575);
DISPLAY 1.021277 (2250 4575);
DISPLAY INVISIBLE (2250 4575);
FORCEADD OFFPAGE..5
(2525 4775);
FORCEPROP 2 LAST $XR0 160 
J 0
(2270 4775);
DISPLAY 0.638298 (2270 4775);
PAINT MONO (2270 4775);
FORCEPROP 2 LAST CDS_LIB standard
J 0
(2525 4775);
PAINT MONO (2525 4775);
DISPLAY INVISIBLE (2525 4775);
FORCEPROP 1 LAST OFFPAGE TRUE
J 0
(2850 4650);
DISPLAY 0.872340 (2850 4650);
PAINT GREEN (2850 4650);
DISPLAY INVISIBLE (2850 4650);
FORCEPROP 1 LAST COMMENT_BODY TRUE
J 0
(2625 4700);
DISPLAY 0.872340 (2625 4700);
PAINT GREEN (2625 4700);
DISPLAY INVISIBLE (2625 4700);
FORCEPROP 2 LAST PATH I9
J 0
(2250 4825);
DISPLAY 1.021277 (2250 4825);
DISPLAY INVISIBLE (2250 4825);
FORCEADD CAD_NOTE..1
(6350 150);
FORCEPROP 0 LAST S1 PLACE THE BULK CAPS CLOSE TO SLOT
J 0
(6200 25);
DISPLAY 0.808511 (6200 25);
PAINT WHITE (6200 25);
FORCEPROP 2 LAST CDS_LIB logical_power
J 0
(6350 150);
PAINT MONO (6350 150);
DISPLAY INVISIBLE (6350 150);
FORCEPROP 1 LAST COMMENT_BODY TRUE
J 0
(6375 250);
DISPLAY 0.978723 (6375 250);
DISPLAY INVISIBLE (6375 250);
FORCEADD DNS..2
(300 -200);
PAINT RED (300 -200);
FORCEPROP 2 LAST CDS_LIB mstr_misc
J 0
(300 -200);
PAINT MONO (300 -200);
DISPLAY INVISIBLE (300 -200);
FORCEPROP 1 LAST COMMENT_BODY TRUE
R 1
J 0
(375 -425);
DISPLAY 0.872340 (375 -425);
PAINT GREEN (375 -425);
DISPLAY INVISIBLE (375 -425);
FORCEADD DNS..2
(775 325);
PAINT RED (775 325);
FORCEPROP 2 LAST CDS_LIB mstr_misc
J 0
(775 325);
PAINT MONO (775 325);
DISPLAY INVISIBLE (775 325);
FORCEPROP 1 LAST COMMENT_BODY TRUE
R 1
J 0
(850 100);
DISPLAY 0.872340 (850 100);
PAINT GREEN (850 100);
DISPLAY INVISIBLE (850 100);
FORCEADD QUANTA_TITLE_BLOCK_C..1
(9275 -900);
FORCEPROP 0 LAST CDS_CON_LAST_MODIFIED Fri Aug 25 14:02:26 2023
J 0
(7390 -885);
PAINT MONO (7390 -885);
DISPLAY INVISIBLE (7390 -885);
FORCEPROP 1 LAST CUSTOM_TXT_CDS <CON_LAST_MODIFIED>
J 0
(7390 -885);
DISPLAY 0.978723 (7390 -885);
FORCEPROP 2 LAST CUSTOM_TXT_CDS <XR_PAGE_TITLE>
J 0
(1385 4350);
DISPLAY 0.638298 (1385 4350);
PAINT PINK (1385 4350);
DISPLAY INVISIBLE (1385 4350);
FORCEPROP 2 LAST CUSTOM_TXT_CDS <Q_NUMBER>
J 0
(7872 -797);
DISPLAY 1.212766 (7872 -797);
FORCEPROP 2 LAST CUSTOM_TXT_CDS <Q_PROJ>
J 0
(6893 -798);
DISPLAY 1.212766 (6893 -798);
FORCEPROP 2 LAST CUSTOM_TXT_CDS <Q_REV>
J 0
(9091 -797);
DISPLAY 1.212766 (9091 -797);
FORCEPROP 2 LAST CUSTOM_TXT_CDS <CON_PAGE_NUM> OF <CON_TOTAL_PAGES>
J 0
(8829 -882);
DISPLAY 0.978723 (8829 -882);
FORCEPROP 2 LAST CUSTOM_TXT_CDS <NAME_2>
J 0
(6100 -850);
FORCEPROP 2 LAST CUSTOM_TXT_CDS <NAME_1>
J 0
(6100 -725);
FORCEPROP 1 LAST Q_TITLE PCIE - V3_2 OCP3.0_X16(1/3)
J 0
(0 -825);
DISPLAY 1.957447 (0 -825);
PAINT GREEN (0 -825);
FORCEPROP 1 LAST Q_DEPT 
J 1
(5512 -851);
DISPLAY 1.957447 (5512 -851);
PAINT GREEN (5512 -851);
FORCEPROP 2 LAST CDS_XR_PAGE_TITLE CR-159 : @S9S_MB_2U_LIB.S9S_MB_2U(SCH_1):PAGE159
J 0
(1385 4350);
DISPLAY 0.638298 (1385 4350);
PAINT PINK (1385 4350);
DISPLAY INVISIBLE (1385 4350);
FORCEPROP 1 LAST COMMENT_BODY TRUE
J 0
(9287 -913);
DISPLAY 0.978723 (9287 -913);
PAINT GREEN (9287 -913);
DISPLAY INVISIBLE (9287 -913);
FORCEPROP 2 LAST PAGE_BORDER TRUE
J 0
(1385 4350);
DISPLAY 0.638298 (1385 4350);
PAINT PINK (1385 4350);
DISPLAY INVISIBLE (1385 4350);
FORCEPROP 1 LAST CDS_LMAN_SYM_OUTLINE -9475,6775,100,-125
J 0
(9275 -900);
DISPLAY 0.468085 (9275 -900);
PAINT GREEN (9275 -900);
DISPLAY INVISIBLE (9275 -900);
FORCEPROP 2 LAST CDS_LIB pure_quanta
J 0
(9275 -900);
PAINT MONO (9275 -900);
DISPLAY INVISIBLE (9275 -900);
WIRE 17 -1 (5675 1850)(5675 2000);
WIRE 17 -1 (5675 1700)(5675 1850);
WIRE 17 -1 (5675 2000)(5675 2350);
WIRE 17 -1 (5675 2500)(5675 2350);
WIRE 17 -1 (5675 1700)(5675 1550);
WIRE 17 -1 (5675 1550)(5675 1400);
WIRE 17 -1 (5675 2500)(5675 2650);
WIRE 17 -1 (5675 2650)(5675 2800);
WIRE 17 -1 (5675 1400)(5675 1250);
WIRE 17 -1 (5675 1250)(5675 1100);
WIRE 17 -1 (5675 2800)(5675 3100);
WIRE 17 -1 (5675 3100)(5675 3250);
WIRE 17 -1 (5675 950)(5675 1100);
WIRE 17 -1 (5675 3400)(5675 3250);
WIRE 17 -1 (5675 3550)(5675 3400);
WIRE 17 -1 (6775 3550)(5675 3550);
FORCEPROP 2 LAST SIG_NAME P5E_CPU1_PE1_RX_DP<15:0>
J 0
(5915 3560);
DISPLAY 0.638298 (5915 3560);
PAINT WHITE (5915 3560);
WIRE 17 -1 (5825 2550)(5825 2700);
WIRE 17 -1 (5825 2400)(5825 2550);
WIRE 17 -1 (5825 2700)(5825 2850);
WIRE 17 -1 (5825 2850)(5825 3150);
WIRE 17 -1 (5825 2050)(5825 2400);
WIRE 17 -1 (5825 1900)(5825 2050);
WIRE 17 -1 (5825 3300)(5825 3150);
WIRE 17 -1 (5825 3450)(5825 3300);
WIRE 17 -1 (5825 1750)(5825 1900);
WIRE 17 -1 (5825 1750)(5825 1600);
WIRE 17 -1 (5825 3600)(5825 3450);
WIRE 17 -1 (6775 3600)(5825 3600);
FORCEPROP 2 LAST SIG_NAME P5E_CPU1_PE1_RX_DN<15:0>
J 0
(5915 3610);
DISPLAY 0.638298 (5915 3610);
PAINT WHITE (5915 3610);
WIRE 17 -1 (5825 1600)(5825 1450);
WIRE 17 -1 (5825 1450)(5825 1300);
WIRE 17 -1 (5825 1300)(5825 1150);
WIRE 17 -1 (3225 1300)(3225 1400);
WIRE 17 -1 (3225 1100)(3225 1300);
WIRE 17 -1 (3225 1600)(3225 1400);
WIRE 17 -1 (3225 1700)(3225 1600);
WIRE 17 -1 (3225 1100)(3225 1000);
WIRE 17 -1 (3225 1700)(3225 1900);
WIRE 17 -1 (3225 1900)(3225 2000);
WIRE 17 -1 (3225 2000)(3225 2400);
WIRE 17 -1 (3225 2400)(3225 2500);
WIRE 17 -1 (3225 2500)(3225 2700);
WIRE 17 -1 (3225 2700)(3225 2800);
WIRE 17 -1 (3225 2800)(3225 3150);
WIRE 17 -1 (3225 3150)(3225 3250);
WIRE 17 -1 (3225 3250)(3225 3450);
WIRE 17 -1 (3225 3450)(3225 3550);
WIRE 17 -1 (2125 3550)(3225 3550);
FORCEPROP 2 LAST SIG_NAME P5E_CPU1_PE1_TX_C_DN<15:0>
J 0
(2190 3560);
DISPLAY 0.680851 (2190 3560);
PAINT WHITE (2190 3560);
WIRE 17 -1 (5825 1000)(5825 1150);
WIRE 17 -1 (3075 2550)(3075 2650);
WIRE 17 -1 (3075 2350)(3075 2550);
WIRE 17 -1 (3075 2650)(3075 2850);
WIRE 17 -1 (3075 2850)(3075 3100);
WIRE 17 -1 (3075 2050)(3075 2350);
WIRE 17 -1 (3075 1850)(3075 2050);
WIRE 17 -1 (3075 3100)(3075 3300);
WIRE 17 -1 (3075 3300)(3075 3400);
WIRE 17 -1 (3075 1750)(3075 1850);
WIRE 17 -1 (3075 1750)(3075 1550);
WIRE 17 -1 (3075 3400)(3075 3600);
WIRE 17 -1 (3075 3600)(2125 3600);
FORCEPROP 2 LAST SIG_NAME P5E_CPU1_PE1_TX_C_DP<15:0>
J 0
(2190 3610);
DISPLAY 0.680851 (2190 3610);
PAINT WHITE (2190 3610);
WIRE 17 -1 (3075 1550)(3075 1450);
WIRE 17 -1 (3075 1250)(3075 1450);
WIRE 17 -1 (3075 1150)(3075 1250);
WIRE 17 -1 (3075 1150)(3075 950);
WIRE 16 -1 (300 600)(300 550);
WIRE 16 -1 (4225 50)(4225 -50);
WIRE 16 -1 (7925 50)(7925 -25);
WIRE 16 -1 (2575 3875)(2575 4225);
WIRE 16 -1 (3850 3875)(2575 3875);
WIRE 16 -1 (3550 5450)(3550 4375);
WIRE 16 -1 (5725 50)(5725 -25);
WIRE 16 -1 (325 2600)(325 2500);
WIRE 16 -1 (325 2800)(325 2600);
WIRE 16 -1 (700 2600)(325 2600);
WIRE 16 -1 (4225 -650)(4225 -575);
WIRE 16 -1 (5325 425)(5325 275);
WIRE 16 -1 (5325 475)(5325 425);
WIRE 16 -1 (5150 425)(5325 425);
WIRE 16 -1 (7975 3450)(7975 3575);
WIRE 16 -1 (3675 875)(3675 275);
WIRE 16 -1 (3675 1025)(3675 875);
WIRE 16 -1 (3850 875)(3675 875);
WIRE 16 -1 (775 -350)(775 -275);
WIRE 16 -1 (300 -350)(300 -275);
WIRE 16 -1 (7425 -525)(7425 -475);
WIRE 16 -1 (8725 -525)(8725 -475);
WIRE 16 -1 (5150 4675)(6225 4675);
FORCEPROP 2 LAST SIG_NAME CLK_100M_OCP_V3_2_D_DN
J 0
(5440 4685);
DISPLAY 0.553191 (5440 4685);
PAINT WHITE (5440 4685);
WIRE 16 -1 (5150 4525)(6225 4525);
FORCEPROP 2 LAST SIG_NAME CLK_50M_NCSI_OCP_V3_2_ISO
J 0
(5440 4535);
DISPLAY 0.510638 (5440 4535);
PAINT WHITE (5440 4535);
WIRE 16 -1 (6500 4075)(7650 4075);
FORCEPROP 2 LAST SIG_NAME SMB_OCP_V3_2_3V3AUX_BUF_SCL
J 0
(6965 4085);
DISPLAY 0.553191 (6965 4085);
PAINT WHITE (6965 4085);
WIRE 16 -1 (6500 4025)(7650 4025);
FORCEPROP 2 LAST SIG_NAME SMB_OCP_V3_2_3V3AUX_BUF_SDA
J 0
(6965 4035);
DISPLAY 0.553191 (6965 4035);
PAINT WHITE (6965 4035);
WIRE 16 -1 (5150 3975)(7650 3975);
FORCEPROP 2 LAST SIG_NAME RST_SMB_OCP_V3_2_N
J 0
(5915 3985);
DISPLAY 0.553191 (5915 3985);
PAINT WHITE (5915 3985);
WIRE 16 -1 (6300 4075)(5150 4075);
FORCEPROP 2 LAST SIG_NAME SMB_OCP_V3_2_3V3AUX_BUF_R_SCL
J 0
(5340 4085);
DISPLAY 0.553191 (5340 4085);
PAINT WHITE (5340 4085);
WIRE 16 -1 (6300 4025)(5150 4025);
FORCEPROP 2 LAST SIG_NAME SMB_OCP_V3_2_3V3AUX_BUF_R_SDA
J 0
(5340 4035);
DISPLAY 0.553191 (5340 4035);
PAINT WHITE (5340 4035);
WIRE 16 -1 (7975 3925)(5150 3925);
FORCEPROP 2 LAST SIG_NAME OCP_V3_1_PRSNTA_R_N
J 0
(5915 3935);
DISPLAY 0.510638 (5915 3935);
PAINT WHITE (5915 3935);
WIRE 16 -1 (7975 3775)(7975 3925);
WIRE 16 -1 (6750 3875)(5150 3875);
FORCEPROP 2 LAST SIG_NAME RST_PERST1_OCP_V3_2_N
J 0
(5915 3885);
DISPLAY 0.553191 (5915 3885);
PAINT WHITE (5915 3885);
WIRE 16 -1 (5150 3825)(6750 3825);
FORCEPROP 2 LAST SIG_NAME OCP_V3_2_PRSNT2_R_N
J 0
(5915 3835);
DISPLAY 0.553191 (5915 3835);
PAINT WHITE (5915 3835);
WIRE 16 -1 (5150 4625)(6225 4625);
FORCEPROP 2 LAST SIG_NAME CLK_100M_OCP_V3_2_D_DP
J 0
(5440 4635);
DISPLAY 0.553191 (5440 4635);
PAINT WHITE (5440 4635);
WIRE 16 -1 (5150 3675)(6750 3675);
FORCEPROP 2 LAST SIG_NAME CLK_100M_OCP_V3_2_B_DP
J 0
(5915 3685);
DISPLAY 0.680851 (5915 3685);
PAINT WHITE (5915 3685);
WIRE 16 -1 (5150 3725)(6750 3725);
FORCEPROP 2 LAST SIG_NAME CLK_100M_OCP_V3_2_B_DN
J 0
(5915 3735);
DISPLAY 0.680851 (5915 3735);
PAINT WHITE (5915 3735);
WIRE 16 -1 (5150 1125)(5725 1125);
WIRE 16 -1 (5150 1075)(5575 1075);
WIRE 16 -1 (5150 475)(5325 475);
WIRE 16 -1 (5325 525)(5325 475);
WIRE 16 -1 (5150 525)(5325 525);
WIRE 16 -1 (5150 575)(5325 575);
WIRE 16 -1 (5325 575)(5325 525);
WIRE 16 -1 (5150 625)(5325 625);
WIRE 16 -1 (5325 625)(5325 575);
WIRE 16 -1 (5325 875)(5325 625);
WIRE 16 -1 (5150 875)(5325 875);
WIRE 16 -1 (5325 1025)(5325 875);
WIRE 16 -1 (5150 1025)(5325 1025);
WIRE 16 -1 (5150 1175)(5325 1175);
WIRE 16 -1 (5325 1175)(5325 1025);
WIRE 16 -1 (5325 1325)(5325 1175);
WIRE 16 -1 (5150 1325)(5325 1325);
WIRE 16 -1 (5150 1475)(5325 1475);
WIRE 16 -1 (5325 1475)(5325 1325);
WIRE 16 -1 (5325 1625)(5325 1475);
WIRE 16 -1 (5150 1625)(5325 1625);
WIRE 16 -1 (5150 1775)(5325 1775);
WIRE 16 -1 (5325 1775)(5325 1625);
WIRE 16 -1 (5325 1925)(5325 1775);
WIRE 16 -1 (5150 1925)(5325 1925);
WIRE 16 -1 (5325 2075)(5325 1925);
WIRE 16 -1 (5150 2075)(5325 2075);
WIRE 16 -1 (5150 2275)(5325 2275);
WIRE 16 -1 (5325 2275)(5325 2075);
WIRE 16 -1 (5325 2425)(5325 2275);
WIRE 16 -1 (5150 2425)(5325 2425);
WIRE 16 -1 (5325 2575)(5325 2425);
WIRE 16 -1 (5150 2575)(5325 2575);
WIRE 16 -1 (5150 2725)(5325 2725);
WIRE 16 -1 (5325 2725)(5325 2575);
WIRE 16 -1 (5325 2875)(5325 2725);
WIRE 16 -1 (5150 2875)(5325 2875);
WIRE 16 -1 (5150 3025)(5325 3025);
WIRE 16 -1 (5325 3025)(5325 2875);
WIRE 16 -1 (5325 3175)(5325 3025);
WIRE 16 -1 (5150 3175)(5325 3175);
WIRE 16 -1 (5150 3325)(5325 3325);
WIRE 16 -1 (5325 3325)(5325 3175);
WIRE 16 -1 (5325 3475)(5325 3325);
WIRE 16 -1 (5150 3475)(5325 3475);
WIRE 16 -1 (5325 3625)(5325 3475);
WIRE 16 -1 (5150 3625)(5325 3625);
WIRE 16 -1 (5150 3775)(5325 3775);
WIRE 16 -1 (5325 3775)(5325 3625);
WIRE 16 -1 (5325 4125)(5325 3775);
WIRE 16 -1 (5150 4125)(5325 4125);
WIRE 16 -1 (5150 4175)(5325 4175);
WIRE 16 -1 (5325 4175)(5325 4125);
WIRE 16 -1 (5150 4225)(5325 4225);
WIRE 16 -1 (5325 4225)(5325 4175);
WIRE 16 -1 (5150 4275)(5325 4275);
WIRE 16 -1 (5325 4275)(5325 4225);
WIRE 16 -1 (5150 4325)(5325 4325);
WIRE 16 -1 (5325 4325)(5325 4275);
WIRE 16 -1 (5325 4375)(5325 4325);
WIRE 16 -1 (5150 4375)(5325 4375);
WIRE 16 -1 (5150 4575)(5325 4575);
WIRE 16 -1 (5325 4575)(5325 4375);
WIRE 16 -1 (5325 4725)(5325 4575);
WIRE 16 -1 (5150 4725)(5325 4725);
WIRE 16 -1 (3325 975)(3850 975);
WIRE 16 -1 (3850 925)(3175 925);
WIRE 16 -1 (2125 825)(3850 825);
FORCEPROP 2 LAST SIG_NAME TP_OCP_V3_2_B68
J 0
(2190 835);
DISPLAY 0.680851 (2190 835);
PAINT WHITE (2190 835);
WIRE 16 -1 (2125 775)(3850 775);
FORCEPROP 2 LAST SIG_NAME TP_OCP_V3_2_B69
J 0
(2190 785);
DISPLAY 0.680851 (2190 785);
PAINT WHITE (2190 785);
WIRE 16 -1 (2100 2600)(900 2600);
FORCEPROP 0 LAST CDS_PHYS_NET_NAME FM_OCP_SFF_PWR_GOOD
J 0
(1265 2642);
PAINT MONO (1265 2642);
DISPLAY INVISIBLE (1265 2642);
FORCEPROP 2 LAST SIG_NAME FM_OCP_V3_2_PWR_GOOD
J 0
(1340 2610);
DISPLAY 0.680851 (1340 2610);
PAINT WHITE (1340 2610);
WIRE 16 -1 (2450 3675)(3850 3675);
FORCEPROP 2 LAST SIG_NAME CLK_100M_OCP_V3_2_A_DP
J 0
(2515 3685);
DISPLAY 0.553191 (2515 3685);
PAINT WHITE (2515 3685);
WIRE 16 -1 (2075 4075)(3850 4075);
FORCEPROP 2 LAST SIG_NAME OCP_V3_2_BIF0_R_N
J 0
(2690 4085);
DISPLAY 0.553191 (2690 4085);
PAINT WHITE (2690 4085);
WIRE 16 -1 (1075 3825)(1875 3825);
FORCEPROP 2 LAST SIG_NAME OCP_V3_2_AUX_PWR_EN
J 0
(1140 3835);
DISPLAY 0.553191 (1140 3835);
PAINT WHITE (1140 3835);
WIRE 16 -1 (3850 3825)(2075 3825);
FORCEPROP 2 LAST SIG_NAME OCP_V3_2_AUX_PWR_EN_R
J 0
(2515 3835);
DISPLAY 0.553191 (2515 3835);
PAINT WHITE (2515 3835);
WIRE 16 -1 (1075 3925)(3850 3925);
FORCEPROP 2 LAST SIG_NAME RST_PERST0_OCP_V3_2_N
J 0
(1140 3935);
DISPLAY 0.553191 (1140 3935);
PAINT WHITE (1140 3935);
WIRE 16 -1 (2075 3975)(3850 3975);
FORCEPROP 2 LAST SIG_NAME OCP_V3_2_BIF2_R_N
J 0
(2690 3985);
DISPLAY 0.553191 (2690 3985);
PAINT WHITE (2690 3985);
WIRE 16 -1 (2450 3725)(3850 3725);
FORCEPROP 2 LAST SIG_NAME CLK_100M_OCP_V3_2_A_DN
J 0
(2515 3735);
DISPLAY 0.553191 (2515 3735);
PAINT WHITE (2515 3735);
WIRE 16 -1 (3850 1025)(3675 1025);
WIRE 16 -1 (3675 1175)(3675 1025);
WIRE 16 -1 (3850 1175)(3675 1175);
WIRE 16 -1 (3675 1325)(3675 1175);
WIRE 16 -1 (3850 1325)(3675 1325);
WIRE 16 -1 (3675 1475)(3675 1325);
WIRE 16 -1 (3850 1475)(3675 1475);
WIRE 16 -1 (3675 1625)(3675 1475);
WIRE 16 -1 (3850 1625)(3675 1625);
WIRE 16 -1 (3675 1775)(3675 1625);
WIRE 16 -1 (3850 1775)(3675 1775);
WIRE 16 -1 (3675 1925)(3675 1775);
WIRE 16 -1 (3850 1925)(3675 1925);
WIRE 16 -1 (3675 2075)(3675 1925);
WIRE 16 -1 (3850 2075)(3675 2075);
WIRE 16 -1 (3675 2275)(3675 2075);
WIRE 16 -1 (3850 2275)(3675 2275);
WIRE 16 -1 (3675 2425)(3675 2275);
WIRE 16 -1 (3850 2425)(3675 2425);
WIRE 16 -1 (3675 2575)(3675 2425);
WIRE 16 -1 (3850 2575)(3675 2575);
WIRE 16 -1 (3675 2725)(3675 2575);
WIRE 16 -1 (3850 2725)(3675 2725);
WIRE 16 -1 (3675 2875)(3675 2725);
WIRE 16 -1 (3850 2875)(3675 2875);
WIRE 16 -1 (3675 3025)(3675 2875);
WIRE 16 -1 (3850 3025)(3675 3025);
WIRE 16 -1 (3675 3175)(3675 3025);
WIRE 16 -1 (3850 3175)(3675 3175);
WIRE 16 -1 (3675 3325)(3675 3175);
WIRE 16 -1 (3850 3325)(3675 3325);
WIRE 16 -1 (3675 3475)(3675 3325);
WIRE 16 -1 (3850 3475)(3675 3475);
WIRE 16 -1 (3675 3625)(3675 3475);
WIRE 16 -1 (3850 3625)(3675 3625);
WIRE 16 -1 (3675 3625)(3675 3775);
WIRE 16 -1 (3850 3775)(3675 3775);
WIRE 16 -1 (3675 3775)(3675 4575);
WIRE 16 -1 (3850 4575)(3675 4575);
WIRE 16 -1 (3675 4575)(3675 4725);
WIRE 16 -1 (3850 4725)(3675 4725);
WIRE 16 -1 (2075 4025)(3850 4025);
FORCEPROP 2 LAST SIG_NAME OCP_V3_2_BIF1_R_N
J 0
(2690 4035);
DISPLAY 0.553191 (2690 4035);
PAINT WHITE (2690 4035);
WIRE 16 -1 (2575 4825)(3850 4825);
FORCEPROP 2 LAST SIG_NAME NCSI_OCP_V3_2_RXD1
J 0
(2640 4835);
DISPLAY 0.553191 (2640 4835);
PAINT WHITE (2640 4835);
WIRE 16 -1 (2575 4675)(3850 4675);
FORCEPROP 2 LAST SIG_NAME CLK_100M_OCP_V3_2_C_DN
J 0
(2640 4685);
DISPLAY 0.553191 (2640 4685);
PAINT WHITE (2640 4685);
WIRE 16 -1 (2575 4625)(3850 4625);
FORCEPROP 2 LAST SIG_NAME CLK_100M_OCP_V3_2_C_DP
J 0
(2640 4635);
DISPLAY 0.553191 (2640 4635);
PAINT WHITE (2640 4635);
WIRE 16 -1 (3550 4125)(3850 4125);
WIRE 16 -1 (3550 4175)(3550 4125);
WIRE 16 -1 (3850 4175)(3550 4175);
WIRE 16 -1 (3550 4225)(3550 4175);
WIRE 16 -1 (3850 4225)(3550 4225);
WIRE 16 -1 (3550 4275)(3550 4225);
WIRE 16 -1 (3850 4275)(3550 4275);
WIRE 16 -1 (3550 4325)(3550 4275);
WIRE 16 -1 (3850 4325)(3550 4325);
WIRE 16 -1 (3550 4375)(3550 4325);
WIRE 16 -1 (3850 4375)(3550 4375);
WIRE 16 -1 (3850 4525)(2575 4525);
FORCEPROP 2 LAST SIG_NAME NCSI_OCP_V3_2_CRS_DV
J 0
(2640 4535);
DISPLAY 0.553191 (2640 4535);
PAINT WHITE (2640 4535);
WIRE 16 -1 (5150 4775)(6225 4775);
FORCEPROP 2 LAST SIG_NAME NCSI_OCP_V3_2_TXD0
J 0
(5440 4785);
DISPLAY 0.553191 (5440 4785);
PAINT WHITE (5440 4785);
WIRE 16 -1 (5150 4825)(6225 4825);
FORCEPROP 2 LAST SIG_NAME NCSI_OCP_V3_2_TXD1
J 0
(5440 4835);
DISPLAY 0.553191 (5440 4835);
PAINT WHITE (5440 4835);
WIRE 16 -1 (5150 4875)(6225 4875);
FORCEPROP 2 LAST SIG_NAME NCSI_OCP_V3_2_TX_EN
J 0
(5440 4885);
DISPLAY 0.553191 (5440 4885);
PAINT WHITE (5440 4885);
WIRE 16 -1 (3175 3575)(3850 3575);
WIRE 16 -1 (2050 2900)(850 2900);
FORCEPROP 0 LAST CDS_PHYS_NET_NAME OCP_SFF_AUX_PWR_EN
J 0
(1215 2942);
PAINT MONO (1215 2942);
DISPLAY INVISIBLE (1215 2942);
FORCEPROP 2 LAST SIG_NAME OCP_V3_2_AUX_PWR_EN
J 0
(1290 2910);
DISPLAY 0.680851 (1290 2910);
PAINT WHITE (1290 2910);
WIRE 16 -1 (5150 725)(6400 725);
FORCEPROP 2 LAST SIG_NAME OCP_V3_2_PWRBRK_N
J 0
(5640 735);
DISPLAY 0.638298 (5640 735);
PAINT WHITE (5640 735);
WIRE 16 -1 (5150 775)(6775 775);
FORCEPROP 2 LAST SIG_NAME USB2_5_R1_DP
J 0
(5640 785);
DISPLAY 0.638298 (5640 785);
PAINT WHITE (5640 785);
WIRE 16 -1 (5150 1525)(5575 1525);
WIRE 16 -1 (5150 1425)(5725 1425);
WIRE 16 -1 (775 -75)(775 50);
WIRE 16 -1 (775 50)(1325 50);
FORCEPROP 2 LAST SIG_NAME OCP_V3_2_ID1
J 0
(890 60);
DISPLAY 0.680851 (890 60);
PAINT WHITE (890 60);
WIRE 16 -1 (775 250)(775 50);
WIRE 16 -1 (300 -75)(300 100);
WIRE 16 -1 (300 100)(300 250);
WIRE 16 -1 (300 100)(1325 100);
FORCEPROP 2 LAST SIG_NAME OCP_V3_2_ID0
J 0
(890 110);
DISPLAY 0.680851 (890 110);
PAINT WHITE (890 110);
WIRE 16 -1 (300 550)(300 450);
WIRE 16 -1 (775 550)(300 550);
WIRE 16 -1 (775 450)(775 550);
WIRE 16 -1 (2275 725)(3850 725);
FORCEPROP 2 LAST SIG_NAME OCP_V3_2_PRSNT3_R_N
J 0
(2340 735);
DISPLAY 0.680851 (2340 735);
PAINT WHITE (2340 735);
WIRE 16 -1 (3175 3075)(3850 3075);
WIRE 16 -1 (3325 3125)(3850 3125);
WIRE 16 -1 (3175 3375)(3850 3375);
FORCEPROP 0 LAST $PNN P5E_CPU1_PE1_TX_C_DP<1>
J 0
(3512 3375);
DISPLAY INVISIBLE (3512 3375);
WIRE 16 -1 (3325 3425)(3850 3425);
FORCEPROP 0 LAST $PNN P5E_CPU1_PE1_TX_C_DN<1>
J 0
(3587 3425);
DISPLAY INVISIBLE (3587 3425);
WIRE 16 -1 (3325 3525)(3850 3525);
WIRE 16 -1 (5150 3075)(5575 3075);
WIRE 16 -1 (7925 -25)(7925 -150);
WIRE 16 -1 (7925 -25)(8175 -25);
WIRE 16 -1 (8175 -25)(8175 -150);
WIRE 16 -1 (8175 -25)(8450 -25);
WIRE 16 -1 (8450 -25)(8450 -150);
WIRE 16 -1 (8450 -25)(8725 -25);
WIRE 16 -1 (8725 -25)(8725 -150);
WIRE 16 -1 (7925 -350)(7925 -475);
WIRE 16 -1 (7925 -475)(8175 -475);
WIRE 16 -1 (8175 -475)(8175 -350);
WIRE 16 -1 (8450 -475)(8175 -475);
WIRE 16 -1 (8450 -475)(8450 -350);
WIRE 16 -1 (8725 -475)(8450 -475);
WIRE 16 -1 (8725 -475)(8725 -350);
WIRE 16 -1 (5725 -350)(5725 -475);
WIRE 16 -1 (5725 -475)(6000 -475);
WIRE 16 -1 (6000 -475)(6000 -350);
WIRE 16 -1 (6400 -475)(6000 -475);
WIRE 16 -1 (6400 -475)(6400 -350);
WIRE 16 -1 (6400 -475)(6675 -475);
WIRE 16 -1 (6675 -475)(6675 -350);
WIRE 16 -1 (6950 -475)(6675 -475);
WIRE 16 -1 (6950 -475)(6950 -350);
WIRE 16 -1 (7175 -475)(6950 -475);
WIRE 16 -1 (7175 -350)(7175 -475);
WIRE 16 -1 (7175 -475)(7425 -475);
WIRE 16 -1 (7425 -475)(7425 -350);
WIRE 16 -1 (7425 -25)(7425 -150);
WIRE 16 -1 (7175 -150)(7175 -25);
WIRE 16 -1 (7175 -25)(7425 -25);
WIRE 16 -1 (6950 -25)(6950 -150);
WIRE 16 -1 (6950 -25)(7175 -25);
WIRE 16 -1 (6675 -25)(6675 -150);
WIRE 16 -1 (6675 -25)(6950 -25);
WIRE 16 -1 (6400 -25)(6400 -150);
WIRE 16 -1 (6400 -25)(6675 -25);
WIRE 16 -1 (6000 -25)(6000 -150);
WIRE 16 -1 (6400 -25)(6000 -25);
WIRE 16 -1 (5725 -25)(6000 -25);
WIRE 16 -1 (5725 -150)(5725 -25);
WIRE 16 -1 (3325 1075)(3850 1075);
WIRE 16 -1 (3175 1125)(3850 1125);
WIRE 16 -1 (3175 1225)(3850 1225);
WIRE 16 -1 (3325 1275)(3850 1275);
WIRE 16 -1 (5725 3125)(5150 3125);
WIRE 16 -1 (5150 2775)(5575 2775);
WIRE 16 -1 (5150 2625)(5575 2625);
WIRE 16 -1 (5150 2525)(5725 2525);
WIRE 16 -1 (3175 2025)(3850 2025);
WIRE 16 -1 (5150 1275)(5725 1275);
WIRE 16 -1 (5150 1225)(5575 1225);
WIRE 16 -1 (3800 -575)(4225 -575);
WIRE 16 -1 (3775 -50)(4225 -50);
WIRE 16 -1 (3775 -225)(4225 -225);
WIRE 16 -1 (4225 -225)(4225 -50);
WIRE 16 -1 (4225 -225)(4225 -400);
WIRE 16 -1 (3800 -400)(4225 -400);
WIRE 16 -1 (325 2900)(650 2900);
WIRE 16 -1 (325 2900)(325 2800);
WIRE 16 -1 (650 2800)(325 2800);
WIRE 16 -1 (5150 1825)(5575 1825);
WIRE 16 -1 (5150 1725)(5725 1725);
WIRE 16 -1 (5150 825)(6775 825);
FORCEPROP 2 LAST SIG_NAME USB2_5_R1_DN
J 0
(5640 835);
DISPLAY 0.638298 (5640 835);
PAINT WHITE (5640 835);
WIRE 16 -1 (5725 2025)(5150 2025);
WIRE 16 -1 (5150 2225)(6725 2225);
FORCEPROP 2 LAST SIG_NAME OCP_V3_2_PRSNT1_R_N
J 0
(5890 2235);
DISPLAY 0.680851 (5890 2235);
PAINT WHITE (5890 2235);
WIRE 16 -1 (5150 975)(5725 975);
WIRE 16 -1 (5150 925)(5575 925);
WIRE 16 -1 (8300 775)(6975 775);
FORCEPROP 2 LAST SIG_NAME USB2_5_DP
J 0
(7440 785);
DISPLAY 0.638298 (7440 785);
PAINT WHITE (7440 785);
WIRE 16 -1 (6975 825)(8300 825);
FORCEPROP 2 LAST SIG_NAME USB2_5_DN
J 0
(7440 835);
DISPLAY 0.638298 (7440 835);
PAINT WHITE (7440 835);
WIRE 16 -1 (5725 1575)(5150 1575);
WIRE 16 -1 (5150 1675)(5575 1675);
WIRE 16 -1 (2475 -50)(3575 -50);
FORCEPROP 2 LAST SIG_NAME SGPIO_OCP_V3_2_LD_N
J 0
(2590 -40);
DISPLAY 0.680851 (2590 -40);
PAINT WHITE (2590 -40);
WIRE 16 -1 (2475 -225)(3575 -225);
FORCEPROP 2 LAST SIG_NAME SGPIO_OCP_V3_2_DATAIN
J 0
(2590 -215);
DISPLAY 0.680851 (2590 -215);
PAINT WHITE (2590 -215);
WIRE 16 -1 (2475 -575)(3600 -575);
FORCEPROP 2 LAST SIG_NAME SGPIO_OCP_V3_2_DATAOUT
J 0
(2590 -565);
DISPLAY 0.680851 (2590 -565);
PAINT WHITE (2590 -565);
WIRE 16 -1 (2475 -400)(3600 -400);
FORCEPROP 2 LAST SIG_NAME SGPIO_OCP_V3_2_CLK
J 0
(2590 -390);
DISPLAY 0.680851 (2590 -390);
PAINT WHITE (2590 -390);
WIRE 16 -1 (2575 4775)(3850 4775);
FORCEPROP 2 LAST SIG_NAME NCSI_OCP_V3_2_RXD0
J 0
(2640 4785);
DISPLAY 0.553191 (2640 4785);
PAINT WHITE (2640 4785);
WIRE 16 -1 (2575 4925)(3850 4925);
FORCEPROP 2 LAST SIG_NAME SGPIO_OCP_V3_2_CLK
J 0
(2640 4935);
DISPLAY 0.553191 (2640 4935);
PAINT WHITE (2640 4935);
WIRE 16 -1 (2575 4975)(3850 4975);
FORCEPROP 2 LAST SIG_NAME SGPIO_OCP_V3_2_DATAOUT
J 0
(2640 4985);
DISPLAY 0.553191 (2640 4985);
PAINT WHITE (2640 4985);
WIRE 16 -1 (2575 5075)(3850 5075);
FORCEPROP 2 LAST SIG_NAME SGPIO_OCP_V3_2_LD_N
J 0
(2640 5085);
DISPLAY 0.553191 (2640 5085);
PAINT WHITE (2640 5085);
WIRE 16 -1 (2075 5125)(3850 5125);
FORCEPROP 2 LAST SIG_NAME OCP_V3_2_MAIN_PWR_EN_R
J 0
(2640 5135);
DISPLAY 0.553191 (2640 5135);
PAINT WHITE (2640 5135);
WIRE 16 -1 (850 5175)(3850 5175);
FORCEPROP 2 LAST SIG_NAME FM_OCP_V3_2_PWR_GOOD
J 0
(2640 5185);
DISPLAY 0.553191 (2640 5185);
PAINT WHITE (2640 5185);
WIRE 16 -1 (1075 4025)(1875 4025);
FORCEPROP 2 LAST SIG_NAME OCP_V3_2_ISO_BIF1_EN
J 0
(1140 4035);
DISPLAY 0.553191 (1140 4035);
PAINT WHITE (1140 4035);
WIRE 16 -1 (1075 4075)(1875 4075);
FORCEPROP 2 LAST SIG_NAME OCP_V3_2_ISO_BIF0_EN
J 0
(1140 4085);
DISPLAY 0.553191 (1140 4085);
PAINT WHITE (1140 4085);
WIRE 16 -1 (1875 5125)(850 5125);
FORCEPROP 2 LAST SIG_NAME OCP_V3_2_MAIN_PWR_EN
J 0
(915 5135);
DISPLAY 0.553191 (915 5135);
PAINT WHITE (915 5135);
WIRE 16 -1 (2575 4875)(3850 4875);
FORCEPROP 2 LAST SIG_NAME OCP_V3_2_ID0
J 0
(2640 4885);
DISPLAY 0.553191 (2640 4885);
PAINT WHITE (2640 4885);
WIRE 16 -1 (5150 4975)(6225 4975);
FORCEPROP 2 LAST SIG_NAME OCP_V3_2_ISO2_RBT_ARB_OUT
J 0
(5440 4985);
DISPLAY 0.553191 (5440 4985);
PAINT WHITE (5440 4985);
WIRE 16 -1 (5150 5025)(6225 5025);
FORCEPROP 2 LAST SIG_NAME OCP_V3_2_ISO1_RBT_ARB_IN
J 0
(5440 5035);
DISPLAY 0.553191 (5440 5035);
PAINT WHITE (5440 5035);
WIRE 16 -1 (5150 5075)(6225 5075);
FORCEPROP 2 LAST SIG_NAME IRQ_LVC3_OCP_V3_2_WAKE_N
J 0
(5440 5085);
DISPLAY 0.553191 (5440 5085);
PAINT WHITE (5440 5085);
WIRE 16 -1 (6225 5125)(5150 5125);
FORCEPROP 2 LAST SIG_NAME RST_PERST3_OCP_V3_2_N
J 0
(5440 5135);
DISPLAY 0.553191 (5440 5135);
PAINT WHITE (5440 5135);
WIRE 16 -1 (6225 5175)(5150 5175);
FORCEPROP 2 LAST SIG_NAME RST_PERST2_OCP_V3_2_N
J 0
(5440 5185);
DISPLAY 0.553191 (5440 5185);
PAINT WHITE (5440 5185);
WIRE 16 -1 (3175 3275)(3850 3275);
WIRE 16 -1 (3325 3225)(3850 3225);
WIRE 16 -1 (2050 2800)(850 2800);
FORCEPROP 0 LAST CDS_PHYS_NET_NAME OCP_SFF_MAIN_PWR_EN
J 0
(1215 2842);
PAINT MONO (1215 2842);
DISPLAY INVISIBLE (1215 2842);
FORCEPROP 2 LAST SIG_NAME OCP_V3_2_MAIN_PWR_EN
J 0
(1290 2810);
DISPLAY 0.680851 (1290 2810);
PAINT WHITE (1290 2810);
WIRE 16 -1 (2575 5025)(3850 5025);
FORCEPROP 2 LAST SIG_NAME SGPIO_OCP_V3_2_DATAIN
J 0
(2640 5035);
DISPLAY 0.553191 (2640 5035);
PAINT WHITE (2640 5035);
WIRE 16 -1 (5150 3375)(5575 3375);
WIRE 16 -1 (3325 2375)(3850 2375);
FORCEPROP 0 LAST $PNN P5E_CPU1_PE1_TX_C_DN<7>
J 0
(3587 2375);
DISPLAY INVISIBLE (3587 2375);
WIRE 16 -1 (3175 2325)(3850 2325);
WIRE 16 -1 (2450 2225)(3850 2225);
FORCEPROP 2 LAST SIG_NAME OCP_V3_2_PRSNT0_R_N
J 0
(2515 2235);
DISPLAY 0.553191 (2515 2235);
PAINT WHITE (2515 2235);
WIRE 16 -1 (3325 1575)(3850 1575);
WIRE 16 -1 (3175 1725)(3850 1725);
WIRE 16 -1 (3325 1875)(3850 1875);
FORCEPROP 0 LAST $PNN P5E_CPU1_PE1_TX_C_DN<9>
J 0
(3587 1875);
DISPLAY INVISIBLE (3587 1875);
WIRE 16 -1 (3325 2675)(3850 2675);
FORCEPROP 0 LAST $PNN P5E_CPU1_PE1_TX_C_DN<5>
J 0
(3587 2675);
DISPLAY INVISIBLE (3587 2675);
WIRE 16 -1 (3175 2825)(3850 2825);
WIRE 16 -1 (3175 1825)(3850 1825);
WIRE 16 -1 (3325 2775)(3850 2775);
WIRE 16 -1 (3175 2625)(3850 2625);
WIRE 16 -1 (3325 2475)(3850 2475);
WIRE 16 -1 (3325 1975)(3850 1975);
WIRE 16 -1 (3325 1675)(3850 1675);
WIRE 16 -1 (3175 1425)(3850 1425);
WIRE 16 -1 (3175 1525)(3850 1525);
WIRE 16 -1 (3175 2525)(3850 2525);
WIRE 16 -1 (5150 1875)(5725 1875);
WIRE 16 -1 (5150 1375)(5575 1375);
WIRE 16 -1 (3325 1375)(3850 1375);
WIRE 16 -1 (5150 2325)(5575 2325);
WIRE 16 -1 (5150 2375)(5725 2375);
WIRE 16 -1 (5150 3575)(5725 3575);
WIRE 16 -1 (5150 4925)(6225 4925);
FORCEPROP 2 LAST SIG_NAME OCP_V3_2_ID1
J 0
(5440 4935);
DISPLAY 0.553191 (5440 4935);
PAINT WHITE (5440 4935);
WIRE 16 -1 (5150 3525)(5575 3525);
WIRE 16 -1 (5150 3425)(5725 3425);
WIRE 16 -1 (5150 3275)(5725 3275);
WIRE 16 -1 (5150 3225)(5575 3225);
WIRE 16 -1 (5150 2825)(5725 2825);
WIRE 16 -1 (5150 2675)(5725 2675);
WIRE 16 -1 (5150 2475)(5575 2475);
WIRE 16 -1 (5150 1975)(5575 1975);
WIRE 16 -1 (1075 3975)(1875 3975);
FORCEPROP 2 LAST SIG_NAME OCP_V3_2_ISO_BIF2_EN
J 0
(1140 3985);
DISPLAY 0.553191 (1140 3985);
PAINT WHITE (1140 3985);
DOT 1 (3550 4325);
DOT 1 (3550 4375);
DOT 1 (3675 4575);
DOT 1 (5325 3025);
DOT 1 (3675 3325);
DOT 1 (4225 -225);
DOT 1 (3675 875);
DOT 1 (5325 1175);
DOT 1 (3675 1325);
DOT 1 (5325 1325);
DOT 1 (3675 1475);
DOT 1 (5325 1475);
DOT 1 (3675 1625);
DOT 1 (3675 1775);
DOT 1 (3675 1925);
DOT 1 (5325 1925);
DOT 1 (5325 2075);
DOT 1 (3675 2425);
DOT 1 (5325 2425);
DOT 1 (5325 2575);
DOT 1 (5325 2725);
DOT 1 (3675 2875);
DOT 1 (5325 2875);
DOT 1 (5325 3175);
DOT 1 (5325 3325);
DOT 1 (5325 3475);
DOT 1 (5325 3625);
DOT 1 (5325 3775);
DOT 1 (5325 4125);
DOT 1 (3550 4175);
DOT 1 (5325 4175);
DOT 1 (3550 4225);
DOT 1 (5325 4225);
DOT 1 (5325 4275);
DOT 1 (5325 4375);
DOT 1 (775 50);
DOT 1 (300 550);
DOT 1 (300 100);
DOT 1 (5325 2275);
DOT 1 (5325 4575);
DOT 1 (4225 -50);
DOT 1 (325 2600);
DOT 1 (325 2800);
DOT 1 (3675 2275);
DOT 1 (3550 4275);
DOT 1 (3675 2575);
DOT 1 (3675 1175);
DOT 1 (5325 875);
DOT 1 (5325 625);
DOT 1 (5325 575);
DOT 1 (5325 525);
DOT 1 (5325 475);
DOT 1 (5325 425);
DOT 1 (8175 -25);
DOT 1 (7925 -25);
DOT 1 (7175 -25);
DOT 1 (6950 -25);
DOT 1 (6675 -25);
DOT 1 (6400 -25);
DOT 1 (6000 -25);
DOT 1 (8725 -475);
DOT 1 (8450 -475);
DOT 1 (8175 -475);
DOT 1 (7425 -475);
DOT 1 (7175 -475);
DOT 1 (6950 -475);
DOT 1 (6675 -475);
DOT 1 (6400 -475);
DOT 1 (6000 -475);
DOT 1 (3675 2725);
DOT 1 (5725 -25);
DOT 1 (5325 1625);
DOT 1 (3675 2075);
DOT 1 (3675 3475);
DOT 1 (3675 3025);
DOT 1 (3675 3175);
DOT 1 (5325 1025);
DOT 1 (5325 1775);
DOT 1 (3675 1025);
DOT 1 (8450 -25);
DOT 1 (3675 3625);
DOT 1 (5325 4325);
DOT 1 (3675 3775);
FORCENOTE
20230503 CHANGE R3228 TO 200 OHM
(5750 4225) 0;
DISPLAY LEFT (5750 4225);
DISPLAY 1.021277 (5750 4225);
PAINT PINK (5750 4225);
FORCENOTE
20230414 CHANGE R3229 TO 200 OHM
(5750 4275) 0;
DISPLAY LEFT (5750 4275);
DISPLAY 1.021277 (5750 4275);
PAINT PINK (5750 4275);
FORCENOTE
DP/DN SWAP
(2575 3475) 0;
DISPLAY LEFT (2575 3475);
DISPLAY 1.021277 (2575 3475);
FORCENOTE
DP/DN SWAP
(2575 2500) 0;
DISPLAY LEFT (2575 2500);
DISPLAY 1.021277 (2575 2500);
FORCENOTE
DP/DN SWAP
(2575 1100) 0;
DISPLAY LEFT (2575 1100);
DISPLAY 1.021277 (2575 1100);
FORCENOTE
FROM CPU1 PCIE PORT1 [15:0]
(850 3250) 0;
DISPLAY LEFT (850 3250);
DISPLAY 1.276596 (850 3250);
PAINT SKYBLUE (850 3250);
FORCENOTE
DP/DN SWAP
(2575 1400) 0;
DISPLAY LEFT (2575 1400);
DISPLAY 1.021277 (2575 1400);
FORCENOTE
DP/DN SWAP
(2575 1700) 0;
DISPLAY LEFT (2575 1700);
DISPLAY 1.021277 (2575 1700);
FORCENOTE
DP/DN SWAP
(2575 2000) 0;
DISPLAY LEFT (2575 2000);
DISPLAY 1.021277 (2575 2000);
FORCENOTE
FRU ADDRESS:0X52
(200 -625) 0;
DISPLAY LEFT (200 -625);
DISPLAY 1.595745 (200 -625);
PAINT WHITE (200 -625);
FORCENOTE
DP/DN SWAP
(2575 2800) 0;
DISPLAY LEFT (2575 2800);
DISPLAY 1.021277 (2575 2800);
FORCENOTE
DP/DN SWAP
(2575 3225) 0;
DISPLAY LEFT (2575 3225);
DISPLAY 1.021277 (2575 3225);
FORCENOTE
TO CPU1 PCIE PORT1 [15:0]
(6125 3200) 0;
DISPLAY LEFT (6125 3200);
DISPLAY 1.276596 (6125 3200);
PAINT SKYBLUE (6125 3200);
FORCENOTE
20210824 MODIFY FOR GT
(5175 5500) 0;
DISPLAY LEFT (5175 5500);
DISPLAY 2.510638 (5175 5500);
PAINT PINK (5175 5500);
FORCENOTE
$CDS_IMAGE|clipboard_2_2.jpg|2418|537
(1175 1150) 0;
DISPLAY LEFT (1175 1150);
QUIT
